FILE_TYPE = MACRO_DRAWING;
SET COLOR_WIRE YELLOW;
SET COLOR_PROP ORANGE;
SET COLOR_DOT WHITE;
SET COLOR_ARC YELLOW;
SET COLOR_BODY GREEN;
SET COLOR_NOTE PURPLE;
SET PROP_DISPLAY VALUE;
SET PAGE_NUMBER P84;
FORCEADD OFFPAGE..1
(-8375 1925);
FORCEPROP 2 LASTPIN (-8325 1925) SIG_NAME FM_SMB_RST_E1S_0_N
J 0
(-8335 1935);
DISPLAY 0.489362 (-8335 1935);
FORCEPROP 2 LAST $XR0 82 
J 0
(-8626 1925);
DISPLAY 0.638298 (-8626 1925);
PAINT MONO (-8626 1925);
FORCEPROP 2 LAST CDS_LIB standard
J 0
(-8375 1925);
DISPLAY INVISIBLE (-8375 1925);
FORCEPROP 1 LAST OFFPAGE TRUE
J 0
(-8050 1800);
DISPLAY 0.872340 (-8050 1800);
PAINT GREEN (-8050 1800);
DISPLAY INVISIBLE (-8050 1800);
FORCEPROP 1 LAST COMMENT_BODY TRUE
J 0
(-8250 1825);
DISPLAY 0.872340 (-8250 1825);
PAINT GREEN (-8250 1825);
DISPLAY INVISIBLE (-8250 1825);
FORCEPROP 2 LAST PATH I1
J 0
(-8575 1975);
DISPLAY 0.680851 (-8575 1975);
DISPLAY INVISIBLE (-8575 1975);
FORCEADD OFFPAGE..2
(-575 3850);
FORCEPROP 2 LAST $XR0 82 
J 0
(-386 3850);
DISPLAY 0.638298 (-386 3850);
PAINT MONO (-386 3850);
FORCEPROP 2 LAST CDS_LIB standard
J 0
(-575 3850);
DISPLAY INVISIBLE (-575 3850);
FORCEPROP 1 LAST OFFPAGE TRUE
J 0
(-250 3725);
DISPLAY 0.872340 (-250 3725);
PAINT GREEN (-250 3725);
DISPLAY INVISIBLE (-250 3725);
FORCEPROP 1 LAST COMMENT_BODY TRUE
J 0
(-620 3755);
DISPLAY 0.872340 (-620 3755);
PAINT GREEN (-620 3755);
DISPLAY INVISIBLE (-620 3755);
FORCEPROP 2 LAST PATH I100
J 0
(-375 3900);
DISPLAY 0.680851 (-375 3900);
DISPLAY INVISIBLE (-375 3900);
FORCEADD Q_CAP..1
(-925 3625);
FORCEPROP 1 LAST LOCATION C8005
J 0
(-875 3725);
DISPLAY 0.638298 (-875 3725);
FORCEPROP 0 LAST $SEC 1
J 0
(-875 3775);
DISPLAY 0.680851 (-875 3775);
PAINT MONO (-875 3775);
DISPLAY INVISIBLE (-875 3775);
FORCEPROP 0 LAST CDS_SEC 1
J 0
(-875 3775);
DISPLAY 0.680851 (-875 3775);
DISPLAY INVISIBLE (-875 3775);
FORCEPROP 1 LASTPIN (-925 3725) $PN 1
J 0
(-915 3705);
DISPLAY 0.787234 (-915 3705);
PAINT MONO (-915 3705);
FORCEPROP 1 LASTPIN (-925 3525) $PN 2
J 0
(-915 3505);
DISPLAY 0.787234 (-915 3505);
PAINT MONO (-915 3505);
FORCEPROP 1 LAST VALUE 0.1UF
J 0
(-875 3675);
DISPLAY 0.638298 (-875 3675);
FORCEPROP 1 LAST VOLTAGE 25V
J 0
(-875 3625);
DISPLAY 0.638298 (-875 3625);
FORCEPROP 1 LAST TOLERANCE 10%
J 0
(-875 3575);
DISPLAY 0.638298 (-875 3575);
FORCEPROP 1 LAST MATERIAL X7R
J 0
(-875 3525);
DISPLAY 0.638298 (-875 3525);
FORCEPROP 1 LAST PACK_TYPE 0402
J 0
(-875 3425);
DISPLAY 0.638298 (-875 3425);
FORCEPROP 2 LAST CDS_LIB pure_quanta
J 0
(-925 3625);
DISPLAY INVISIBLE (-925 3625);
FORCEPROP 1 LAST PATH I101
J 0
(-875 3775);
DISPLAY 0.978723 (-875 3775);
PAINT WHITE (-875 3775);
DISPLAY INVISIBLE (-875 3775);
FORCEPROP 1 LAST PART_NUMBER CH4104K1B00
J 0
(-875 3475);
DISPLAY 0.638298 (-875 3475);
DISPLAY INVISIBLE (-875 3475);
FORCEADD UNIVERSAL_GND..1
(-925 3300);
FORCEPROP 3 LASTPIN (-925 3350) SIG_NAME GND\g
J 0
(-915 3360);
DISPLAY 0.659574 (-915 3360);
PAINT MONO (-915 3360);
DISPLAY INVISIBLE (-915 3360);
FORCEPROP 2 LAST CDS_LIB pure_quanta_power
J 0
(-925 3300);
DISPLAY INVISIBLE (-925 3300);
FORCEPROP 1 LAST HDL_POWER GND
J 1
(-900 3225);
DISPLAY 0.872340 (-900 3225);
PAINT GREEN (-900 3225);
DISPLAY INVISIBLE (-900 3225);
FORCEPROP 1 LAST PATH I102
J 0
(-850 3300);
DISPLAY 0.872340 (-850 3300);
PAINT AQUA (-850 3300);
DISPLAY INVISIBLE (-850 3300);
FORCEADD Q_RES..1
R 2
(-1275 3850);
FORCEPROP 1 LAST LOCATION R6118
J 2
(-1400 3850);
DISPLAY 0.489362 (-1400 3850);
PAINT SKYBLUE (-1400 3850);
FORCEPROP 0 LAST $SEC 1
J 0
(-1400 3900);
DISPLAY 0.680851 (-1400 3900);
PAINT MONO (-1400 3900);
DISPLAY INVISIBLE (-1400 3900);
FORCEPROP 0 LAST CDS_SEC 1
J 0
(-1400 3900);
DISPLAY 1.021277 (-1400 3900);
DISPLAY INVISIBLE (-1400 3900);
FORCEPROP 1 LASTPIN (-1175 3850) $PN 1
J 2
(-1187 3862);
DISPLAY 0.489362 (-1187 3862);
PAINT MONO (-1187 3862);
FORCEPROP 1 LASTPIN (-1375 3850) $PN 2
J 2
(-1337 3862);
DISPLAY 0.489362 (-1337 3862);
PAINT MONO (-1337 3862);
FORCEPROP 1 LAST VALUE 0
J 0
(-1150 3850);
DISPLAY 0.489362 (-1150 3850);
PAINT SKYBLUE (-1150 3850);
FORCEPROP 1 LAST PACK_TYPE 0402LF
J 0
(-1450 3775);
DISPLAY 0.489362 (-1450 3775);
PAINT SKYBLUE (-1450 3775);
DISPLAY INVISIBLE (-1450 3775);
FORCEPROP 1 LAST TOLERANCE 5%
J 2
(-1150 3825);
DISPLAY 0.489362 (-1150 3825);
PAINT SKYBLUE (-1150 3825);
DISPLAY INVISIBLE (-1150 3825);
FORCEPROP 1 LAST MATERIAL CHIP
J 0
(-1450 3825);
DISPLAY 0.489362 (-1450 3825);
PAINT SKYBLUE (-1450 3825);
DISPLAY INVISIBLE (-1450 3825);
FORCEPROP 1 LAST WATTAGE 1/16W
J 0
(-1200 3775);
DISPLAY 0.489362 (-1200 3775);
PAINT SKYBLUE (-1200 3775);
DISPLAY INVISIBLE (-1200 3775);
FORCEPROP 2 LAST CDS_LIB pure_quanta
J 0
(-1275 3850);
DISPLAY INVISIBLE (-1275 3850);
FORCEPROP 2 LAST BOM_COST MEM
J 0
(-1300 4000);
DISPLAY 0.744681 (-1300 4000);
PAINT WHITE (-1300 4000);
DISPLAY INVISIBLE (-1300 4000);
FORCEPROP 1 LAST PATH I103
J 2
(-1225 4000);
DISPLAY 0.978723 (-1225 4000);
PAINT WHITE (-1225 4000);
DISPLAY INVISIBLE (-1225 4000);
FORCEPROP 1 LAST PART_NUMBER CS00002JB13
J 0
(-1375 3900);
DISPLAY 0.489362 (-1375 3900);
PAINT SKYBLUE (-1375 3900);
DISPLAY INVISIBLE (-1375 3900);
FORCEADD Q_RES..2
R 2
(-8650 6275);
FORCEPROP 1 LAST LOCATION R1422
J 2
(-8695 6400);
DISPLAY 0.638298 (-8695 6400);
FORCEPROP 0 LAST $SEC 1
J 0
(-8675 6450);
DISPLAY 0.680851 (-8675 6450);
PAINT MONO (-8675 6450);
DISPLAY INVISIBLE (-8675 6450);
FORCEPROP 0 LAST CDS_SEC 1
J 0
(-8675 6450);
DISPLAY 0.680851 (-8675 6450);
DISPLAY INVISIBLE (-8675 6450);
FORCEPROP 1 LASTPIN (-8650 6375) $PN 1
J 2
(-8655 6337);
DISPLAY 0.787234 (-8655 6337);
PAINT MONO (-8655 6337);
FORCEPROP 1 LASTPIN (-8650 6175) $PN 2
J 2
(-8655 6185);
DISPLAY 0.787234 (-8655 6185);
PAINT MONO (-8655 6185);
FORCEPROP 1 LAST VALUE 100
J 2
(-8695 6350);
DISPLAY 0.638298 (-8695 6350);
FORCEPROP 1 LAST TOLERANCE 1%
J 2
(-8695 6300);
DISPLAY 0.638298 (-8695 6300);
FORCEPROP 1 LAST PACK_TYPE 0402LF
J 2
(-8690 6100);
DISPLAY 0.638298 (-8690 6100);
FORCEPROP 1 LAST WATTAGE 1/16W
J 2
(-8690 6250);
DISPLAY 0.638298 (-8690 6250);
FORCEPROP 1 LAST MATERIAL CHIP
J 2
(-8690 6200);
DISPLAY 0.638298 (-8690 6200);
FORCEPROP 2 LAST CDS_LIB pure_quanta
J 2
(-8650 6275);
DISPLAY INVISIBLE (-8650 6275);
FORCEPROP 1 LAST PATH I104
J 2
(-8700 6450);
DISPLAY 0.978723 (-8700 6450);
PAINT WHITE (-8700 6450);
DISPLAY INVISIBLE (-8700 6450);
FORCEPROP 1 LAST PART_NUMBER CS11002FB07
J 2
(-8690 6150);
DISPLAY 0.638298 (-8690 6150);
DISPLAY INVISIBLE (-8690 6150);
FORCEADD UNIVERSAL_GND..1
(-8625 3375);
FORCEPROP 3 LASTPIN (-8625 3425) SIG_NAME GND\g
J 0
(-8615 3435);
DISPLAY 0.659574 (-8615 3435);
PAINT MONO (-8615 3435);
DISPLAY INVISIBLE (-8615 3435);
FORCEPROP 2 LAST CDS_LIB pure_quanta_power
J 0
(-8625 3375);
DISPLAY INVISIBLE (-8625 3375);
FORCEPROP 1 LAST HDL_POWER GND
J 1
(-8600 3300);
DISPLAY 0.872340 (-8600 3300);
PAINT GREEN (-8600 3300);
DISPLAY INVISIBLE (-8600 3300);
FORCEPROP 1 LAST PATH I105
J 0
(-8550 3375);
DISPLAY 0.872340 (-8550 3375);
PAINT AQUA (-8550 3375);
DISPLAY INVISIBLE (-8550 3375);
FORCEADD Q_RES..2
(-8625 3650);
FORCEPROP 1 LAST LOCATION R9025
J 0
(-8580 3775);
DISPLAY 0.978723 (-8580 3775);
FORCEPROP 0 LAST $SEC 1
J 0
(-8575 3825);
DISPLAY 0.680851 (-8575 3825);
PAINT MONO (-8575 3825);
DISPLAY INVISIBLE (-8575 3825);
FORCEPROP 0 LAST CDS_SEC 1
J 0
(-8575 3825);
DISPLAY 0.680851 (-8575 3825);
DISPLAY INVISIBLE (-8575 3825);
FORCEPROP 1 LASTPIN (-8625 3750) $PN 1
J 0
(-8620 3712);
DISPLAY 0.787234 (-8620 3712);
PAINT MONO (-8620 3712);
FORCEPROP 1 LASTPIN (-8625 3550) $PN 2
J 0
(-8620 3560);
DISPLAY 0.787234 (-8620 3560);
PAINT MONO (-8620 3560);
FORCEPROP 1 LAST MATERIAL EMPTY
J 0
(-8585 3575);
DISPLAY 0.510638 (-8585 3575);
PAINT RED (-8585 3575);
FORCEPROP 1 LAST PACK_TYPE 0402LF
J 0
(-8585 3475);
DISPLAY 0.510638 (-8585 3475);
FORCEPROP 1 LAST TOLERANCE 1%
J 0
(-8580 3675);
DISPLAY 0.510638 (-8580 3675);
FORCEPROP 1 LAST WATTAGE 1/16W
J 0
(-8585 3625);
DISPLAY 0.510638 (-8585 3625);
FORCEPROP 1 LAST VALUE 100K
J 0
(-8580 3725);
DISPLAY 0.510638 (-8580 3725);
FORCEPROP 2 LAST CDS_LIB pure_quanta
J 0
(-8625 3650);
DISPLAY INVISIBLE (-8625 3650);
FORCEPROP 1 LAST PATH I106
J 0
(-8575 3825);
DISPLAY 0.978723 (-8575 3825);
PAINT WHITE (-8575 3825);
DISPLAY INVISIBLE (-8575 3825);
FORCEPROP 1 LAST PART_NUMBER CS41002FB09
J 0
(-8585 3525);
DISPLAY 0.510638 (-8585 3525);
DISPLAY INVISIBLE (-8585 3525);
FORCEADD OFFPAGE..4
R 2
(-8900 3850);
FORCEPROP 2 LAST $XR0 263 
J 0
(-9152 3850);
DISPLAY 0.638298 (-9152 3850);
PAINT MONO (-9152 3850);
FORCEPROP 2 LAST $XR1 268 
J 0
(-9272 3850);
DISPLAY 0.638298 (-9272 3850);
PAINT MONO (-9272 3850);
FORCEPROP 2 LAST CDS_LIB standard
J 0
(-8900 3850);
DISPLAY INVISIBLE (-8900 3850);
FORCEPROP 1 LAST OFFPAGE TRUE
J 2
(-9225 3725);
DISPLAY 0.872340 (-9225 3725);
PAINT GREEN (-9225 3725);
DISPLAY INVISIBLE (-9225 3725);
FORCEPROP 1 LAST COMMENT_BODY TRUE
J 2
(-8875 3750);
DISPLAY 0.872340 (-8875 3750);
PAINT GREEN (-8875 3750);
DISPLAY INVISIBLE (-8875 3750);
FORCEPROP 2 LAST PATH I107
J 0
(-9150 3900);
DISPLAY 0.680851 (-9150 3900);
DISPLAY INVISIBLE (-9150 3900);
FORCEADD UNIVERSAL_GND..1
(-7475 3525);
FORCEPROP 3 LASTPIN (-7475 3575) SIG_NAME GND\g
J 0
(-7465 3585);
DISPLAY 0.659574 (-7465 3585);
PAINT MONO (-7465 3585);
DISPLAY INVISIBLE (-7465 3585);
FORCEPROP 2 LAST CDS_LIB pure_quanta_power
J 0
(-7475 3525);
DISPLAY INVISIBLE (-7475 3525);
FORCEPROP 1 LAST HDL_POWER GND
J 1
(-7450 3450);
DISPLAY 0.872340 (-7450 3450);
PAINT GREEN (-7450 3450);
DISPLAY INVISIBLE (-7450 3450);
FORCEPROP 1 LAST PATH I110
J 0
(-7400 3525);
DISPLAY 0.872340 (-7400 3525);
PAINT AQUA (-7400 3525);
DISPLAY INVISIBLE (-7400 3525);
FORCEADD MOSFET_NCH_DUAL..1
(-7525 3900);
FORCEPROP 1 LAST LOCATION Q9003
J 0
(-7374 3874);
DISPLAY 0.723404 (-7374 3874);
PAINT GREEN (-7374 3874);
FORCEPROP 0 LAST $SEC 1
J 0
(-7350 4025);
DISPLAY 0.680851 (-7350 4025);
PAINT MONO (-7350 4025);
DISPLAY INVISIBLE (-7350 4025);
FORCEPROP 0 LAST CDS_SEC 1
J 0
(-7350 4025);
DISPLAY 0.680851 (-7350 4025);
DISPLAY INVISIBLE (-7350 4025);
FORCEPROP 0 LASTPIN (-7475 4100) $PN 6
R 1
J 0
(-7485 4110);
DISPLAY 0.680851 (-7485 4110);
PAINT MONO (-7485 4110);
FORCEPROP 0 LASTPIN (-7725 3850) $PN 2
J 2
(-7735 3860);
DISPLAY 0.680851 (-7735 3860);
PAINT MONO (-7735 3860);
FORCEPROP 0 LASTPIN (-7475 3700) $PN 1
R 1
J 2
(-7485 3690);
DISPLAY 0.680851 (-7485 3690);
PAINT MONO (-7485 3690);
FORCEPROP 2 LAST PART_TYPE SMLF
J 0
(-7350 3975);
DISPLAY 1.021277 (-7350 3975);
FORCEPROP 2 LAST VALUE PJT138K
J 0
(-7350 3925);
DISPLAY 1.021277 (-7350 3925);
FORCEPROP 1 LAST MATERIAL IC
J 0
(-7374 3749);
DISPLAY 0.723404 (-7374 3749);
PAINT GREEN (-7374 3749);
FORCEPROP 1 LAST NEEDS_NO_SIZE TRUE
J 0
(-7525 3899);
DISPLAY 0.468085 (-7525 3899);
PAINT GREEN (-7525 3899);
DISPLAY INVISIBLE (-7525 3899);
FORCEPROP 1 LAST CDS_LMAN_SYM_OUTLINE -150,150,150,-150
J 0
(-7525 3900);
DISPLAY 0.468085 (-7525 3900);
PAINT GREEN (-7525 3900);
DISPLAY INVISIBLE (-7525 3900);
FORCEPROP 2 LAST CDS_LIB pure_quanta
J 0
(-7525 3900);
DISPLAY INVISIBLE (-7525 3900);
FORCEPROP 1 LAST PATH I111
J 0
(-7525 3900);
DISPLAY 0.723404 (-7525 3900);
PAINT GREEN (-7525 3900);
DISPLAY INVISIBLE (-7525 3900);
FORCEPROP 1 LAST PART_NUMBER BAM138K0003
J 0
(-7374 3814);
DISPLAY 0.723404 (-7374 3814);
PAINT GREEN (-7374 3814);
DISPLAY INVISIBLE (-7374 3814);
FORCEADD Q_RES..2
(-7475 4500);
FORCEPROP 1 LAST LOCATION R9026
J 0
(-7430 4625);
DISPLAY 0.638298 (-7430 4625);
FORCEPROP 0 LAST $SEC 1
J 0
(-7425 4675);
DISPLAY 0.680851 (-7425 4675);
PAINT MONO (-7425 4675);
DISPLAY INVISIBLE (-7425 4675);
FORCEPROP 0 LAST CDS_SEC 1
J 0
(-7425 4675);
DISPLAY 0.680851 (-7425 4675);
DISPLAY INVISIBLE (-7425 4675);
FORCEPROP 1 LASTPIN (-7475 4600) $PN 1
J 0
(-7470 4562);
DISPLAY 0.787234 (-7470 4562);
PAINT MONO (-7470 4562);
FORCEPROP 1 LASTPIN (-7475 4400) $PN 2
J 0
(-7470 4410);
DISPLAY 0.787234 (-7470 4410);
PAINT MONO (-7470 4410);
FORCEPROP 1 LAST PACK_TYPE 0402LF
J 0
(-7435 4375);
DISPLAY 0.638298 (-7435 4375);
FORCEPROP 1 LAST TOLERANCE 5%
J 0
(-7430 4525);
DISPLAY 0.638298 (-7430 4525);
FORCEPROP 1 LAST WATTAGE 1/16W
J 0
(-7435 4475);
DISPLAY 0.638298 (-7435 4475);
FORCEPROP 1 LAST MATERIAL CHIP
J 0
(-7435 4425);
DISPLAY 0.638298 (-7435 4425);
FORCEPROP 1 LAST VALUE 4.7K
J 0
(-7430 4575);
DISPLAY 0.638298 (-7430 4575);
FORCEPROP 2 LAST CDS_LIB pure_quanta
J 0
(-7475 4500);
DISPLAY INVISIBLE (-7475 4500);
FORCEPROP 1 LAST PATH I112
J 0
(-7425 4675);
DISPLAY 0.978723 (-7425 4675);
PAINT WHITE (-7425 4675);
DISPLAY INVISIBLE (-7425 4675);
FORCEPROP 1 LAST PART_NUMBER CS24702JB10
J 0
(-7435 4325);
DISPLAY 0.638298 (-7435 4325);
DISPLAY INVISIBLE (-7435 4325);
FORCEADD UNIVERSAL_GND..1
(-6325 3825);
FORCEPROP 3 LASTPIN (-6325 3875) SIG_NAME GND\g
J 0
(-6315 3885);
DISPLAY 0.659574 (-6315 3885);
PAINT MONO (-6315 3885);
DISPLAY INVISIBLE (-6315 3885);
FORCEPROP 2 LAST CDS_LIB pure_quanta_power
J 0
(-6325 3825);
DISPLAY INVISIBLE (-6325 3825);
FORCEPROP 1 LAST HDL_POWER GND
J 1
(-6300 3750);
DISPLAY 0.872340 (-6300 3750);
PAINT GREEN (-6300 3750);
DISPLAY INVISIBLE (-6300 3750);
FORCEPROP 1 LAST PATH I113
J 0
(-6250 3825);
DISPLAY 0.872340 (-6250 3825);
PAINT AQUA (-6250 3825);
DISPLAY INVISIBLE (-6250 3825);
FORCEADD Q_RES..2
(-6325 4625);
FORCEPROP 1 LAST LOCATION R9027
J 0
(-6280 4750);
DISPLAY 0.638298 (-6280 4750);
FORCEPROP 0 LAST $SEC 1
J 0
(-6275 4800);
DISPLAY 0.680851 (-6275 4800);
PAINT MONO (-6275 4800);
DISPLAY INVISIBLE (-6275 4800);
FORCEPROP 0 LAST CDS_SEC 1
J 0
(-6275 4800);
DISPLAY 0.680851 (-6275 4800);
DISPLAY INVISIBLE (-6275 4800);
FORCEPROP 1 LASTPIN (-6325 4725) $PN 1
J 0
(-6320 4687);
DISPLAY 0.787234 (-6320 4687);
PAINT MONO (-6320 4687);
FORCEPROP 1 LASTPIN (-6325 4525) $PN 2
J 0
(-6320 4535);
DISPLAY 0.787234 (-6320 4535);
PAINT MONO (-6320 4535);
FORCEPROP 1 LAST MATERIAL CHIP
J 0
(-6285 4550);
DISPLAY 0.638298 (-6285 4550);
FORCEPROP 1 LAST WATTAGE 1/16W
J 0
(-6285 4600);
DISPLAY 0.638298 (-6285 4600);
FORCEPROP 1 LAST TOLERANCE 1%
J 0
(-6280 4650);
DISPLAY 0.638298 (-6280 4650);
FORCEPROP 1 LAST VALUE 100K
J 0
(-6280 4700);
DISPLAY 0.638298 (-6280 4700);
FORCEPROP 1 LAST PACK_TYPE 0402LF
J 0
(-6285 4500);
DISPLAY 0.638298 (-6285 4500);
FORCEPROP 2 LAST CDS_LIB pure_quanta
J 0
(-6325 4625);
DISPLAY INVISIBLE (-6325 4625);
FORCEPROP 1 LAST PATH I114
J 0
(-6275 4800);
DISPLAY 0.978723 (-6275 4800);
PAINT WHITE (-6275 4800);
DISPLAY INVISIBLE (-6275 4800);
FORCEPROP 1 LAST PART_NUMBER CS41002FB09
J 0
(-6285 4450);
DISPLAY 0.638298 (-6285 4450);
DISPLAY INVISIBLE (-6285 4450);
FORCEADD UNIVERSAL_GND..1
(-5550 3950);
FORCEPROP 3 LASTPIN (-5550 4000) SIG_NAME GND\g
J 0
(-5540 4010);
DISPLAY 0.659574 (-5540 4010);
PAINT MONO (-5540 4010);
DISPLAY INVISIBLE (-5540 4010);
FORCEPROP 2 LAST CDS_LIB pure_quanta_power
J 0
(-5550 3950);
DISPLAY INVISIBLE (-5550 3950);
FORCEPROP 1 LAST HDL_POWER GND
J 1
(-5525 3875);
DISPLAY 0.872340 (-5525 3875);
PAINT GREEN (-5525 3875);
DISPLAY INVISIBLE (-5525 3875);
FORCEPROP 1 LAST PATH I115
J 0
(-5475 3950);
DISPLAY 0.872340 (-5475 3950);
PAINT AQUA (-5475 3950);
DISPLAY INVISIBLE (-5475 3950);
FORCEADD Q_CAP..1
(-5550 4150);
FORCEPROP 1 LAST LOCATION C9005
J 0
(-5500 4250);
DISPLAY 0.978723 (-5500 4250);
FORCEPROP 0 LAST $SEC 1
J 0
(-5500 4300);
DISPLAY 0.680851 (-5500 4300);
PAINT MONO (-5500 4300);
DISPLAY INVISIBLE (-5500 4300);
FORCEPROP 0 LAST CDS_SEC 1
J 0
(-5500 4300);
DISPLAY 0.680851 (-5500 4300);
DISPLAY INVISIBLE (-5500 4300);
FORCEPROP 1 LASTPIN (-5550 4250) $PN 1
J 0
(-5540 4230);
DISPLAY 0.787234 (-5540 4230);
PAINT MONO (-5540 4230);
FORCEPROP 1 LASTPIN (-5550 4050) $PN 2
J 0
(-5540 4030);
DISPLAY 0.787234 (-5540 4030);
PAINT MONO (-5540 4030);
FORCEPROP 1 LAST VOLTAGE 25V
J 0
(-5500 4150);
DISPLAY 0.638298 (-5500 4150);
FORCEPROP 1 LAST VALUE 0.1UF
J 0
(-5500 4200);
DISPLAY 0.638298 (-5500 4200);
FORCEPROP 1 LAST PACK_TYPE 0402
J 0
(-5500 3950);
DISPLAY 0.638298 (-5500 3950);
FORCEPROP 1 LAST TOLERANCE 10%
J 0
(-5500 4100);
DISPLAY 0.638298 (-5500 4100);
FORCEPROP 1 LAST MATERIAL X7R
J 0
(-5500 4050);
DISPLAY 0.638298 (-5500 4050);
PAINT RED (-5500 4050);
FORCEPROP 2 LAST CDS_LIB pure_quanta
J 0
(-5550 4150);
DISPLAY INVISIBLE (-5550 4150);
FORCEPROP 1 LAST PATH I116
J 0
(-5500 4300);
DISPLAY 0.978723 (-5500 4300);
PAINT WHITE (-5500 4300);
DISPLAY INVISIBLE (-5500 4300);
FORCEPROP 1 LAST PART_NUMBER CH4104K1B00
J 0
(-5500 4000);
DISPLAY 0.638298 (-5500 4000);
DISPLAY INVISIBLE (-5500 4000);
FORCEADD OFFPAGE..2
(-5200 4450);
FORCEPROP 2 LAST $XR0 80 
J 0
(-5011 4450);
DISPLAY 0.638298 (-5011 4450);
PAINT MONO (-5011 4450);
FORCEPROP 2 LAST CDS_LIB standard
J 0
(-5200 4450);
DISPLAY INVISIBLE (-5200 4450);
FORCEPROP 1 LAST OFFPAGE TRUE
J 0
(-4875 4325);
DISPLAY 0.872340 (-4875 4325);
PAINT AQUA (-4875 4325);
DISPLAY INVISIBLE (-4875 4325);
FORCEPROP 1 LAST COMMENT_BODY TRUE
J 0
(-5245 4355);
DISPLAY 0.872340 (-5245 4355);
PAINT GREEN (-5245 4355);
DISPLAY INVISIBLE (-5245 4355);
FORCEPROP 2 LAST PATH I117
J 0
(-5000 4500);
DISPLAY 0.680851 (-5000 4500);
DISPLAY INVISIBLE (-5000 4500);
FORCEADD Q_RES..1
(-7075 5075);
FORCEPROP 1 LAST LOCATION R9028
J 0
(-7325 5075);
DISPLAY 0.787234 (-7325 5075);
FORCEPROP 0 LAST $SEC 1
J 0
(-6825 5200);
DISPLAY 0.680851 (-6825 5200);
PAINT MONO (-6825 5200);
DISPLAY INVISIBLE (-6825 5200);
FORCEPROP 0 LAST CDS_SEC 1
J 0
(-6825 5200);
DISPLAY 0.680851 (-6825 5200);
DISPLAY INVISIBLE (-6825 5200);
FORCEPROP 1 LASTPIN (-7175 5075) $PN 1
J 0
(-7163 5087);
DISPLAY 0.787234 (-7163 5087);
PAINT MONO (-7163 5087);
FORCEPROP 1 LASTPIN (-6975 5075) $PN 2
J 0
(-7013 5087);
DISPLAY 0.787234 (-7013 5087);
PAINT MONO (-7013 5087);
FORCEPROP 1 LAST VALUE 0
J 2
(-6950 5075);
DISPLAY 0.510638 (-6950 5075);
FORCEPROP 1 LAST TOLERANCE 5%
J 0
(-6925 5075);
DISPLAY 0.510638 (-6925 5075);
FORCEPROP 1 LAST MATERIAL EMPTY
J 0
(-6850 5075);
DISPLAY 0.510638 (-6850 5075);
PAINT RED (-6850 5075);
FORCEPROP 1 LAST WATTAGE 1/16W
J 2
(-6825 5175);
DISPLAY 0.510638 (-6825 5175);
FORCEPROP 1 LAST PACK_TYPE 0402LF
J 0
(-7175 5175);
DISPLAY 0.510638 (-7175 5175);
FORCEPROP 2 LAST CDS_LIB pure_quanta
J 0
(-7075 5075);
DISPLAY INVISIBLE (-7075 5075);
FORCEPROP 1 LAST PATH I118
J 0
(-7125 5225);
DISPLAY 0.978723 (-7125 5225);
PAINT WHITE (-7125 5225);
DISPLAY INVISIBLE (-7125 5225);
FORCEPROP 1 LAST PART_NUMBER CS00002JB13
J 0
(-7125 5125);
DISPLAY 0.510638 (-7125 5125);
DISPLAY INVISIBLE (-7125 5125);
FORCEADD UNIVERSAL_POWER..1
(-7475 4725);
FORCEPROP 3 LASTPIN (-7475 4675) SIG_NAME P3V3_AUX\g
J 0
(-7465 4685);
DISPLAY 0.659574 (-7465 4685);
PAINT MONO (-7465 4685);
DISPLAY INVISIBLE (-7465 4685);
FORCEPROP 1 LAST HDL_POWER P3V3_AUX
J 1
(-7475 4775);
DISPLAY 0.872340 (-7475 4775);
PAINT GREEN (-7475 4775);
FORCEPROP 2 LAST CDS_LIB pure_quanta_power
J 0
(-7475 4725);
DISPLAY INVISIBLE (-7475 4725);
FORCEPROP 1 LAST PATH I119
J 0
(-7425 4750);
DISPLAY 0.872340 (-7425 4750);
PAINT AQUA (-7425 4750);
DISPLAY INVISIBLE (-7425 4750);
FORCEADD UNIVERSAL_POWER..1
(-6325 4850);
FORCEPROP 3 LASTPIN (-6325 4800) SIG_NAME P3V3_AUX\g
J 0
(-6315 4810);
DISPLAY 0.659574 (-6315 4810);
PAINT MONO (-6315 4810);
DISPLAY INVISIBLE (-6315 4810);
FORCEPROP 1 LAST HDL_POWER P3V3_AUX
J 1
(-6325 4900);
DISPLAY 0.872340 (-6325 4900);
PAINT GREEN (-6325 4900);
FORCEPROP 2 LAST CDS_LIB pure_quanta_power
J 0
(-6325 4850);
DISPLAY INVISIBLE (-6325 4850);
FORCEPROP 1 LAST PATH I120
J 0
(-6275 4875);
DISPLAY 0.872340 (-6275 4875);
PAINT AQUA (-6275 4875);
DISPLAY INVISIBLE (-6275 4875);
FORCEADD MOSFET_NCH_DUAL..2
(-6375 4200);
FORCEPROP 1 LAST LOCATION Q9003
J 0
(-6224 4176);
DISPLAY 0.723404 (-6224 4176);
PAINT GREEN (-6224 4176);
FORCEPROP 0 LAST $SEC 2
J 0
(-6200 4325);
DISPLAY 0.680851 (-6200 4325);
PAINT MONO (-6200 4325);
DISPLAY INVISIBLE (-6200 4325);
FORCEPROP 0 LAST CDS_SEC 2
J 0
(-6200 4325);
DISPLAY 0.680851 (-6200 4325);
DISPLAY INVISIBLE (-6200 4325);
FORCEPROP 0 LASTPIN (-6325 4400) $PN 3
R 1
J 0
(-6335 4410);
DISPLAY 0.680851 (-6335 4410);
PAINT MONO (-6335 4410);
FORCEPROP 0 LASTPIN (-6575 4150) $PN 5
J 2
(-6585 4160);
DISPLAY 0.680851 (-6585 4160);
PAINT MONO (-6585 4160);
FORCEPROP 0 LASTPIN (-6325 4000) $PN 4
R 1
J 2
(-6335 3990);
DISPLAY 0.680851 (-6335 3990);
PAINT MONO (-6335 3990);
FORCEPROP 2 LAST VALUE PJT138K
J 0
(-6200 4225);
DISPLAY 1.021277 (-6200 4225);
FORCEPROP 2 LAST PART_TYPE SMLF
J 0
(-6200 4275);
DISPLAY 1.021277 (-6200 4275);
FORCEPROP 1 LAST MATERIAL IC
J 0
(-6224 4051);
DISPLAY 0.723404 (-6224 4051);
PAINT GREEN (-6224 4051);
FORCEPROP 1 LAST NEEDS_NO_SIZE TRUE
J 0
(-6225 4091);
DISPLAY 0.468085 (-6225 4091);
PAINT GREEN (-6225 4091);
DISPLAY INVISIBLE (-6225 4091);
FORCEPROP 1 LAST CDS_LMAN_SYM_OUTLINE -150,150,150,-150
J 0
(-6375 4200);
DISPLAY 0.468085 (-6375 4200);
PAINT GREEN (-6375 4200);
DISPLAY INVISIBLE (-6375 4200);
FORCEPROP 2 LAST CDS_LIB pure_quanta
J 0
(-6375 4200);
DISPLAY INVISIBLE (-6375 4200);
FORCEPROP 1 LAST PATH I121
J 0
(-6225 4050);
DISPLAY 0.723404 (-6225 4050);
PAINT GREEN (-6225 4050);
DISPLAY INVISIBLE (-6225 4050);
FORCEPROP 1 LAST PART_NUMBER BAM138K0003
J 0
(-6224 4106);
DISPLAY 0.723404 (-6224 4106);
PAINT GREEN (-6224 4106);
DISPLAY INVISIBLE (-6224 4106);
FORCEADD OFFPAGE..2
(-7775 6175);
FORCEPROP 2 LAST $XR2 78 
J 0
(-7406 6175);
DISPLAY 0.638298 (-7406 6175);
PAINT MONO (-7406 6175);
FORCEPROP 2 LAST $XR1 81 
J 0
(-7496 6175);
DISPLAY 0.638298 (-7496 6175);
PAINT MONO (-7496 6175);
FORCEPROP 2 LAST $XR0 55 
J 0
(-7586 6175);
DISPLAY 0.638298 (-7586 6175);
PAINT MONO (-7586 6175);
FORCEPROP 2 LAST CDS_LIB standard
J 0
(-7775 6175);
DISPLAY INVISIBLE (-7775 6175);
FORCEPROP 1 LAST OFFPAGE TRUE
J 0
(-7450 6050);
DISPLAY 0.872340 (-7450 6050);
PAINT GREEN (-7450 6050);
DISPLAY INVISIBLE (-7450 6050);
FORCEPROP 1 LAST COMMENT_BODY TRUE
J 0
(-7820 6080);
DISPLAY 0.872340 (-7820 6080);
PAINT GREEN (-7820 6080);
DISPLAY INVISIBLE (-7820 6080);
FORCEPROP 2 LAST PATH I25
J 0
(-7400 6225);
DISPLAY 0.680851 (-7400 6225);
DISPLAY INVISIBLE (-7400 6225);
FORCEADD OFFPAGE..1
R 2
(-7775 6375);
FORCEPROP 2 LAST $XR2 78 
J 0
(-7409 6375);
DISPLAY 0.638298 (-7409 6375);
PAINT MONO (-7409 6375);
FORCEPROP 2 LAST $XR1 81 
J 0
(-7499 6375);
DISPLAY 0.638298 (-7499 6375);
PAINT MONO (-7499 6375);
FORCEPROP 2 LAST $XR0 28 
J 0
(-7589 6375);
DISPLAY 0.638298 (-7589 6375);
PAINT MONO (-7589 6375);
FORCEPROP 2 LAST CDS_LIB standard
J 0
(-7775 6375);
DISPLAY INVISIBLE (-7775 6375);
FORCEPROP 1 LAST OFFPAGE TRUE
J 2
(-8100 6250);
DISPLAY 0.872340 (-8100 6250);
PAINT GREEN (-8100 6250);
DISPLAY INVISIBLE (-8100 6250);
FORCEPROP 1 LAST COMMENT_BODY TRUE
J 2
(-7900 6275);
DISPLAY 0.872340 (-7900 6275);
PAINT GREEN (-7900 6275);
DISPLAY INVISIBLE (-7900 6275);
FORCEPROP 2 LAST PATH I26
J 0
(-7400 6425);
DISPLAY 0.680851 (-7400 6425);
DISPLAY INVISIBLE (-7400 6425);
FORCEADD Q_RES..2
R 2
(-6525 6300);
FORCEPROP 1 LAST LOCATION R530
J 2
(-6570 6425);
DISPLAY 0.489362 (-6570 6425);
PAINT SKYBLUE (-6570 6425);
FORCEPROP 0 LAST $SEC 1
J 0
(-6550 6475);
DISPLAY 0.680851 (-6550 6475);
PAINT MONO (-6550 6475);
DISPLAY INVISIBLE (-6550 6475);
FORCEPROP 0 LAST CDS_SEC 1
J 0
(-6550 6475);
DISPLAY 0.680851 (-6550 6475);
DISPLAY INVISIBLE (-6550 6475);
FORCEPROP 1 LASTPIN (-6525 6400) $PN 1
J 2
(-6530 6362);
DISPLAY 0.489362 (-6530 6362);
PAINT MONO (-6530 6362);
FORCEPROP 1 LASTPIN (-6525 6200) $PN 2
J 2
(-6530 6210);
DISPLAY 0.489362 (-6530 6210);
PAINT MONO (-6530 6210);
FORCEPROP 1 LAST PACK_TYPE 0402LF
J 2
(-6575 6250);
DISPLAY 0.489362 (-6575 6250);
PAINT SKYBLUE (-6575 6250);
FORCEPROP 1 LAST VALUE 0
J 2
(-6575 6300);
DISPLAY 0.489362 (-6575 6300);
PAINT SKYBLUE (-6575 6300);
FORCEPROP 1 LAST MATERIAL CHIP
J 2
(-6575 6200);
DISPLAY 0.489362 (-6575 6200);
PAINT SKYBLUE (-6575 6200);
FORCEPROP 1 LAST TOLERANCE 5%
J 2
(-6570 6325);
DISPLAY 0.638298 (-6570 6325);
PAINT SKYBLUE (-6570 6325);
DISPLAY INVISIBLE (-6570 6325);
FORCEPROP 1 LAST WATTAGE 1/16W
J 2
(-6565 6275);
DISPLAY 0.638298 (-6565 6275);
PAINT SKYBLUE (-6565 6275);
DISPLAY INVISIBLE (-6565 6275);
FORCEPROP 2 LAST CDS_LIB pure_quanta
J 2
(-6525 6300);
DISPLAY INVISIBLE (-6525 6300);
FORCEPROP 1 LAST PATH I27
J 2
(-6575 6475);
DISPLAY 0.978723 (-6575 6475);
PAINT WHITE (-6575 6475);
DISPLAY INVISIBLE (-6575 6475);
FORCEPROP 1 LAST PART_NUMBER CS00002JB13
J 2
(-6565 6175);
DISPLAY 0.638298 (-6565 6175);
PAINT SKYBLUE (-6565 6175);
DISPLAY INVISIBLE (-6565 6175);
FORCEADD OFFPAGE..6
R 2
(-5700 6400);
FORCEPROP 2 LAST $XR1 81 
J 0
(-5396 6400);
DISPLAY 0.638298 (-5396 6400);
PAINT MONO (-5396 6400);
FORCEPROP 2 LAST $XR0 28 
J 0
(-5486 6400);
DISPLAY 0.638298 (-5486 6400);
PAINT MONO (-5486 6400);
FORCEPROP 2 LAST CDS_LIB mstr_standard
J 2
(-5700 6400);
DISPLAY INVISIBLE (-5700 6400);
FORCEPROP 1 LAST OFFPAGE TRUE
J 2
(-6025 6275);
DISPLAY 0.872340 (-6025 6275);
PAINT GREEN (-6025 6275);
DISPLAY INVISIBLE (-6025 6275);
FORCEPROP 1 LAST COMMENT_BODY TRUE
J 2
(-5800 6325);
DISPLAY 0.872340 (-5800 6325);
PAINT GREEN (-5800 6325);
DISPLAY INVISIBLE (-5800 6325);
FORCEPROP 2 LAST PATH I28
J 0
(-5375 6450);
DISPLAY 0.680851 (-5375 6450);
DISPLAY INVISIBLE (-5375 6450);
FORCEADD OFFPAGE..3
(-5700 6200);
FORCEPROP 2 LAST $XR1 81 
J 0
(-5396 6200);
DISPLAY 0.638298 (-5396 6200);
PAINT MONO (-5396 6200);
FORCEPROP 2 LAST $XR0 55 
J 0
(-5486 6200);
DISPLAY 0.638298 (-5486 6200);
PAINT MONO (-5486 6200);
FORCEPROP 2 LAST CDS_LIB standard
J 2
(-5700 6200);
DISPLAY INVISIBLE (-5700 6200);
FORCEPROP 1 LAST OFFPAGE TRUE
J 0
(-5375 6075);
DISPLAY 0.872340 (-5375 6075);
PAINT GREEN (-5375 6075);
DISPLAY INVISIBLE (-5375 6075);
FORCEPROP 1 LAST COMMENT_BODY TRUE
J 0
(-5750 6100);
DISPLAY 0.872340 (-5750 6100);
PAINT PEACH (-5750 6100);
DISPLAY INVISIBLE (-5750 6100);
FORCEPROP 2 LAST PATH I29
J 0
(-5375 6250);
DISPLAY 0.680851 (-5375 6250);
DISPLAY INVISIBLE (-5375 6250);
FORCEADD UNIVERSAL_POWER..1
(-3925 6300);
FORCEPROP 3 LASTPIN (-3925 6250) SIG_NAME P3V3_AUX\g
J 0
(-3915 6260);
DISPLAY 0.659574 (-3915 6260);
PAINT MONO (-3915 6260);
DISPLAY INVISIBLE (-3915 6260);
FORCEPROP 1 LAST HDL_POWER P3V3_AUX
J 1
(-3925 6350);
DISPLAY 0.489362 (-3925 6350);
PAINT GREEN (-3925 6350);
FORCEPROP 2 LAST BOM_COST OCP3.0 
J 0
(-3925 6400);
DISPLAY 0.680851 (-3925 6400);
DISPLAY INVISIBLE (-3925 6400);
FORCEPROP 2 LAST CDS_LIB pure_quanta_power
J 0
(-3925 6300);
DISPLAY INVISIBLE (-3925 6300);
FORCEPROP 1 LAST PATH I30
J 0
(-3875 6325);
DISPLAY 0.872340 (-3875 6325);
PAINT AQUA (-3875 6325);
DISPLAY INVISIBLE (-3875 6325);
FORCEADD OFFPAGE..2
R 2
(-3500 1525);
FORCEPROP 2 LAST $XR1 80 
J 0
(-3845 1525);
DISPLAY 0.638298 (-3845 1525);
PAINT MONO (-3845 1525);
FORCEPROP 2 LAST $XR0 171 
J 0
(-3755 1525);
DISPLAY 0.638298 (-3755 1525);
PAINT MONO (-3755 1525);
FORCEPROP 2 LAST CDS_LIB standard
J 0
(-3500 1525);
DISPLAY INVISIBLE (-3500 1525);
FORCEPROP 1 LAST OFFPAGE TRUE
J 2
(-3825 1400);
DISPLAY 0.872340 (-3825 1400);
PAINT GREEN (-3825 1400);
DISPLAY INVISIBLE (-3825 1400);
FORCEPROP 1 LAST COMMENT_BODY TRUE
J 2
(-3455 1430);
DISPLAY 0.872340 (-3455 1430);
PAINT GREEN (-3455 1430);
DISPLAY INVISIBLE (-3455 1430);
FORCEPROP 2 LAST PATH I31
J 0
(-3750 1575);
DISPLAY 0.680851 (-3750 1575);
DISPLAY INVISIBLE (-3750 1575);
FORCEADD OFFPAGE..2
R 2
(-3500 1625);
FORCEPROP 2 LAST $XR1 80 
J 0
(-3845 1625);
DISPLAY 0.638298 (-3845 1625);
PAINT MONO (-3845 1625);
FORCEPROP 2 LAST $XR0 171 
J 0
(-3755 1625);
DISPLAY 0.638298 (-3755 1625);
PAINT MONO (-3755 1625);
FORCEPROP 2 LAST CDS_LIB standard
J 0
(-3500 1625);
DISPLAY INVISIBLE (-3500 1625);
FORCEPROP 1 LAST OFFPAGE TRUE
J 2
(-3825 1500);
DISPLAY 0.872340 (-3825 1500);
PAINT GREEN (-3825 1500);
DISPLAY INVISIBLE (-3825 1500);
FORCEPROP 1 LAST COMMENT_BODY TRUE
J 2
(-3455 1530);
DISPLAY 0.872340 (-3455 1530);
PAINT GREEN (-3455 1530);
DISPLAY INVISIBLE (-3455 1530);
FORCEPROP 2 LAST PATH I32
J 0
(-3750 1675);
DISPLAY 0.680851 (-3750 1675);
DISPLAY INVISIBLE (-3750 1675);
FORCEADD OFFPAGE..1
(-3475 1825);
FORCEPROP 2 LAST $XR1 171 
J 0
(-3816 1825);
DISPLAY 0.638298 (-3816 1825);
PAINT MONO (-3816 1825);
FORCEPROP 2 LAST $XR0 80 
J 0
(-3696 1825);
DISPLAY 0.638298 (-3696 1825);
PAINT MONO (-3696 1825);
FORCEPROP 2 LAST CDS_LIB standard
J 0
(-3475 1825);
DISPLAY INVISIBLE (-3475 1825);
FORCEPROP 1 LAST OFFPAGE TRUE
J 0
(-3150 1700);
DISPLAY 0.872340 (-3150 1700);
PAINT GREEN (-3150 1700);
DISPLAY INVISIBLE (-3150 1700);
FORCEPROP 1 LAST COMMENT_BODY TRUE
J 0
(-3350 1725);
DISPLAY 0.872340 (-3350 1725);
PAINT GREEN (-3350 1725);
DISPLAY INVISIBLE (-3350 1725);
FORCEPROP 2 LAST PATH I33
J 0
(-3725 1875);
DISPLAY 0.680851 (-3725 1875);
DISPLAY INVISIBLE (-3725 1875);
FORCEADD OFFPAGE..2
R 2
(-3475 1775);
FORCEPROP 2 LAST $XR1 80 
J 0
(-3850 1775);
DISPLAY 0.638298 (-3850 1775);
PAINT MONO (-3850 1775);
FORCEPROP 2 LAST $XR0 171 
J 0
(-3760 1775);
DISPLAY 0.638298 (-3760 1775);
PAINT MONO (-3760 1775);
FORCEPROP 2 LAST CDS_LIB standard
J 0
(-3475 1775);
DISPLAY INVISIBLE (-3475 1775);
FORCEPROP 1 LAST OFFPAGE TRUE
J 2
(-3800 1650);
DISPLAY 0.872340 (-3800 1650);
PAINT GREEN (-3800 1650);
DISPLAY INVISIBLE (-3800 1650);
FORCEPROP 1 LAST COMMENT_BODY TRUE
J 2
(-3430 1680);
DISPLAY 0.872340 (-3430 1680);
PAINT GREEN (-3430 1680);
DISPLAY INVISIBLE (-3430 1680);
FORCEPROP 2 LAST PATH I34
J 0
(-3725 1825);
DISPLAY 0.680851 (-3725 1825);
DISPLAY INVISIBLE (-3725 1825);
FORCEADD Q_RES..1
R 2
(-2575 1525);
FORCEPROP 1 LAST LOCATION R15
J 2
(-2675 1525);
DISPLAY 0.489362 (-2675 1525);
PAINT SKYBLUE (-2675 1525);
FORCEPROP 0 LAST $SEC 1
J 0
(-2675 1575);
DISPLAY 0.680851 (-2675 1575);
PAINT MONO (-2675 1575);
DISPLAY INVISIBLE (-2675 1575);
FORCEPROP 0 LAST CDS_SEC 1
J 0
(-2675 1575);
DISPLAY 1.021277 (-2675 1575);
DISPLAY INVISIBLE (-2675 1575);
FORCEPROP 1 LASTPIN (-2475 1525) $PN 1
J 2
(-2487 1537);
DISPLAY 0.489362 (-2487 1537);
PAINT MONO (-2487 1537);
FORCEPROP 1 LASTPIN (-2675 1525) $PN 2
J 2
(-2637 1537);
DISPLAY 0.489362 (-2637 1537);
PAINT MONO (-2637 1537);
FORCEPROP 1 LAST VALUE 0
J 0
(-2450 1525);
DISPLAY 0.489362 (-2450 1525);
PAINT SKYBLUE (-2450 1525);
FORCEPROP 1 LAST PACK_TYPE 0402LF
J 0
(-2750 1450);
DISPLAY 0.489362 (-2750 1450);
PAINT SKYBLUE (-2750 1450);
DISPLAY INVISIBLE (-2750 1450);
FORCEPROP 1 LAST TOLERANCE 5%
J 2
(-2450 1500);
DISPLAY 0.489362 (-2450 1500);
PAINT SKYBLUE (-2450 1500);
DISPLAY INVISIBLE (-2450 1500);
FORCEPROP 1 LAST MATERIAL CHIP
J 0
(-2750 1500);
DISPLAY 0.489362 (-2750 1500);
PAINT SKYBLUE (-2750 1500);
DISPLAY INVISIBLE (-2750 1500);
FORCEPROP 1 LAST WATTAGE 1/16W
J 0
(-2500 1450);
DISPLAY 0.489362 (-2500 1450);
PAINT SKYBLUE (-2500 1450);
DISPLAY INVISIBLE (-2500 1450);
FORCEPROP 2 LAST BOM_COST MEM
J 0
(-2600 1675);
DISPLAY 0.744681 (-2600 1675);
PAINT WHITE (-2600 1675);
DISPLAY INVISIBLE (-2600 1675);
FORCEPROP 2 LAST CDS_LIB pure_quanta
J 0
(-2575 1525);
DISPLAY INVISIBLE (-2575 1525);
FORCEPROP 1 LAST PATH I35
J 2
(-2525 1675);
DISPLAY 0.978723 (-2525 1675);
PAINT WHITE (-2525 1675);
DISPLAY INVISIBLE (-2525 1675);
FORCEPROP 1 LAST PART_NUMBER CS00002JB13
J 0
(-2675 1575);
DISPLAY 0.489362 (-2675 1575);
PAINT SKYBLUE (-2675 1575);
DISPLAY INVISIBLE (-2675 1575);
FORCEADD Q_RES..1
R 2
(-2575 1625);
FORCEPROP 1 LAST LOCATION R14
J 2
(-2675 1625);
DISPLAY 0.489362 (-2675 1625);
PAINT SKYBLUE (-2675 1625);
FORCEPROP 0 LAST $SEC 1
J 0
(-2675 1675);
DISPLAY 0.680851 (-2675 1675);
PAINT MONO (-2675 1675);
DISPLAY INVISIBLE (-2675 1675);
FORCEPROP 0 LAST CDS_SEC 1
J 0
(-2675 1675);
DISPLAY 1.021277 (-2675 1675);
DISPLAY INVISIBLE (-2675 1675);
FORCEPROP 1 LASTPIN (-2475 1625) $PN 1
J 2
(-2487 1637);
DISPLAY 0.489362 (-2487 1637);
PAINT MONO (-2487 1637);
FORCEPROP 1 LASTPIN (-2675 1625) $PN 2
J 2
(-2637 1637);
DISPLAY 0.489362 (-2637 1637);
PAINT MONO (-2637 1637);
FORCEPROP 1 LAST VALUE 0
J 0
(-2450 1625);
DISPLAY 0.489362 (-2450 1625);
PAINT SKYBLUE (-2450 1625);
FORCEPROP 1 LAST PACK_TYPE 0402LF
J 0
(-2750 1550);
DISPLAY 0.489362 (-2750 1550);
PAINT SKYBLUE (-2750 1550);
DISPLAY INVISIBLE (-2750 1550);
FORCEPROP 1 LAST TOLERANCE 5%
J 2
(-2450 1600);
DISPLAY 0.489362 (-2450 1600);
PAINT SKYBLUE (-2450 1600);
DISPLAY INVISIBLE (-2450 1600);
FORCEPROP 1 LAST MATERIAL CHIP
J 0
(-2750 1600);
DISPLAY 0.489362 (-2750 1600);
PAINT SKYBLUE (-2750 1600);
DISPLAY INVISIBLE (-2750 1600);
FORCEPROP 1 LAST WATTAGE 1/16W
J 0
(-2500 1550);
DISPLAY 0.489362 (-2500 1550);
PAINT SKYBLUE (-2500 1550);
DISPLAY INVISIBLE (-2500 1550);
FORCEPROP 2 LAST CDS_LIB pure_quanta
J 0
(-2575 1625);
DISPLAY INVISIBLE (-2575 1625);
FORCEPROP 2 LAST BOM_COST MEM
J 0
(-2600 1775);
DISPLAY 0.744681 (-2600 1775);
PAINT WHITE (-2600 1775);
DISPLAY INVISIBLE (-2600 1775);
FORCEPROP 1 LAST PATH I36
J 2
(-2525 1775);
DISPLAY 0.978723 (-2525 1775);
PAINT WHITE (-2525 1775);
DISPLAY INVISIBLE (-2525 1775);
FORCEPROP 1 LAST PART_NUMBER CS00002JB13
J 0
(-2675 1675);
DISPLAY 0.489362 (-2675 1675);
PAINT SKYBLUE (-2675 1675);
DISPLAY INVISIBLE (-2675 1675);
FORCEADD Q_RES..1
R 2
(-2575 1825);
FORCEPROP 1 LAST LOCATION R9
J 2
(-2675 1825);
DISPLAY 0.489362 (-2675 1825);
PAINT SKYBLUE (-2675 1825);
FORCEPROP 0 LAST $SEC 1
J 0
(-2675 1875);
DISPLAY 0.680851 (-2675 1875);
PAINT MONO (-2675 1875);
DISPLAY INVISIBLE (-2675 1875);
FORCEPROP 0 LAST CDS_SEC 1
J 0
(-2675 1875);
DISPLAY 1.021277 (-2675 1875);
DISPLAY INVISIBLE (-2675 1875);
FORCEPROP 1 LASTPIN (-2475 1825) $PN 1
J 2
(-2487 1837);
DISPLAY 0.489362 (-2487 1837);
PAINT MONO (-2487 1837);
FORCEPROP 1 LASTPIN (-2675 1825) $PN 2
J 2
(-2637 1837);
DISPLAY 0.489362 (-2637 1837);
PAINT MONO (-2637 1837);
FORCEPROP 1 LAST VALUE 0
J 0
(-2450 1825);
DISPLAY 0.489362 (-2450 1825);
PAINT SKYBLUE (-2450 1825);
FORCEPROP 1 LAST PACK_TYPE 0402LF
J 0
(-2750 1750);
DISPLAY 0.489362 (-2750 1750);
PAINT SKYBLUE (-2750 1750);
DISPLAY INVISIBLE (-2750 1750);
FORCEPROP 1 LAST TOLERANCE 5%
J 2
(-2450 1800);
DISPLAY 0.489362 (-2450 1800);
PAINT SKYBLUE (-2450 1800);
DISPLAY INVISIBLE (-2450 1800);
FORCEPROP 1 LAST MATERIAL CHIP
J 0
(-2750 1800);
DISPLAY 0.489362 (-2750 1800);
PAINT SKYBLUE (-2750 1800);
DISPLAY INVISIBLE (-2750 1800);
FORCEPROP 1 LAST WATTAGE 1/16W
J 0
(-2500 1750);
DISPLAY 0.489362 (-2500 1750);
PAINT SKYBLUE (-2500 1750);
DISPLAY INVISIBLE (-2500 1750);
FORCEPROP 2 LAST CDS_LIB pure_quanta
J 0
(-2575 1825);
DISPLAY INVISIBLE (-2575 1825);
FORCEPROP 2 LAST BOM_COST MEM
J 0
(-2600 1975);
DISPLAY 0.744681 (-2600 1975);
PAINT WHITE (-2600 1975);
DISPLAY INVISIBLE (-2600 1975);
FORCEPROP 1 LAST PATH I37
J 2
(-2525 1975);
DISPLAY 0.978723 (-2525 1975);
PAINT WHITE (-2525 1975);
DISPLAY INVISIBLE (-2525 1975);
FORCEPROP 1 LAST PART_NUMBER CS00002JB13
J 0
(-2675 1875);
DISPLAY 0.489362 (-2675 1875);
PAINT SKYBLUE (-2675 1875);
DISPLAY INVISIBLE (-2675 1875);
FORCEADD Q_RES..1
R 2
(-2575 1775);
FORCEPROP 1 LAST LOCATION R13
J 2
(-2675 1775);
DISPLAY 0.489362 (-2675 1775);
PAINT SKYBLUE (-2675 1775);
FORCEPROP 0 LAST $SEC 1
J 0
(-2675 1825);
DISPLAY 0.680851 (-2675 1825);
PAINT MONO (-2675 1825);
DISPLAY INVISIBLE (-2675 1825);
FORCEPROP 0 LAST CDS_SEC 1
J 0
(-2675 1825);
DISPLAY 1.021277 (-2675 1825);
DISPLAY INVISIBLE (-2675 1825);
FORCEPROP 1 LASTPIN (-2475 1775) $PN 1
J 2
(-2487 1787);
DISPLAY 0.489362 (-2487 1787);
PAINT MONO (-2487 1787);
FORCEPROP 1 LASTPIN (-2675 1775) $PN 2
J 2
(-2637 1787);
DISPLAY 0.489362 (-2637 1787);
PAINT MONO (-2637 1787);
FORCEPROP 1 LAST VALUE 0
J 0
(-2450 1775);
DISPLAY 0.489362 (-2450 1775);
PAINT SKYBLUE (-2450 1775);
FORCEPROP 1 LAST PACK_TYPE 0402LF
J 0
(-2750 1700);
DISPLAY 0.489362 (-2750 1700);
PAINT SKYBLUE (-2750 1700);
DISPLAY INVISIBLE (-2750 1700);
FORCEPROP 1 LAST TOLERANCE 5%
J 2
(-2450 1750);
DISPLAY 0.489362 (-2450 1750);
PAINT SKYBLUE (-2450 1750);
DISPLAY INVISIBLE (-2450 1750);
FORCEPROP 1 LAST MATERIAL CHIP
J 0
(-2750 1750);
DISPLAY 0.489362 (-2750 1750);
PAINT SKYBLUE (-2750 1750);
DISPLAY INVISIBLE (-2750 1750);
FORCEPROP 1 LAST WATTAGE 1/16W
J 0
(-2500 1700);
DISPLAY 0.489362 (-2500 1700);
PAINT SKYBLUE (-2500 1700);
DISPLAY INVISIBLE (-2500 1700);
FORCEPROP 2 LAST CDS_LIB pure_quanta
J 0
(-2575 1775);
DISPLAY INVISIBLE (-2575 1775);
FORCEPROP 2 LAST BOM_COST MEM
J 0
(-2600 1925);
DISPLAY 0.744681 (-2600 1925);
PAINT WHITE (-2600 1925);
DISPLAY INVISIBLE (-2600 1925);
FORCEPROP 1 LAST PATH I38
J 2
(-2525 1925);
DISPLAY 0.978723 (-2525 1925);
PAINT WHITE (-2525 1925);
DISPLAY INVISIBLE (-2525 1925);
FORCEPROP 1 LAST PART_NUMBER CS00002JB13
J 0
(-2675 1825);
DISPLAY 0.489362 (-2675 1825);
PAINT SKYBLUE (-2675 1825);
DISPLAY INVISIBLE (-2675 1825);
FORCEADD UNIVERSAL_GND..1
(-1750 1400);
FORCEPROP 3 LASTPIN (-1750 1450) SIG_NAME GND\g
J 0
(-1740 1460);
DISPLAY 0.659574 (-1740 1460);
PAINT MONO (-1740 1460);
DISPLAY INVISIBLE (-1740 1460);
FORCEPROP 2 LAST CDS_LIB pure_quanta_power
J 0
(-1750 1400);
DISPLAY INVISIBLE (-1750 1400);
FORCEPROP 1 LAST HDL_POWER GND
J 1
(-1725 1325);
DISPLAY 0.872340 (-1725 1325);
PAINT GREEN (-1725 1325);
DISPLAY INVISIBLE (-1725 1325);
FORCEPROP 1 LAST PATH I39
J 0
(-1675 1400);
DISPLAY 0.872340 (-1675 1400);
PAINT AQUA (-1675 1400);
DISPLAY INVISIBLE (-1675 1400);
FORCEADD UNIVERSAL_GND..1
(-1850 1925);
FORCEPROP 3 LASTPIN (-1850 1975) SIG_NAME GND\g
J 0
(-1840 1985);
DISPLAY 0.659574 (-1840 1985);
PAINT MONO (-1840 1985);
DISPLAY INVISIBLE (-1840 1985);
FORCEPROP 2 LAST CDS_LIB pure_quanta_power
J 0
(-1850 1925);
DISPLAY INVISIBLE (-1850 1925);
FORCEPROP 1 LAST HDL_POWER GND
J 1
(-1825 1850);
DISPLAY 0.872340 (-1825 1850);
PAINT GREEN (-1825 1850);
DISPLAY INVISIBLE (-1825 1850);
FORCEPROP 1 LAST PATH I40
J 0
(-1775 1925);
DISPLAY 0.872340 (-1775 1925);
PAINT AQUA (-1775 1925);
DISPLAY INVISIBLE (-1775 1925);
FORCEADD CONN8_HBB1081L200D8H..1
(-1475 1700);
FORCEPROP 1 LAST LOCATION J57
J 0
(-1525 2211);
DISPLAY 0.489362 (-1525 2211);
PAINT SKYBLUE (-1525 2211);
FORCEPROP 0 LAST $SEC 1
J 0
(-1525 2250);
DISPLAY 0.680851 (-1525 2250);
PAINT MONO (-1525 2250);
DISPLAY INVISIBLE (-1525 2250);
FORCEPROP 0 LAST CDS_SEC 1
J 0
(-1525 2250);
DISPLAY 1.021277 (-1525 2250);
DISPLAY INVISIBLE (-1525 2250);
FORCEPROP 0 LASTPIN (-1675 1875) $PN 1
J 2
(-1685 1885);
DISPLAY 0.489362 (-1685 1885);
PAINT MONO (-1685 1885);
FORCEPROP 0 LASTPIN (-1675 1825) $PN 2
J 2
(-1685 1835);
DISPLAY 0.489362 (-1685 1835);
PAINT MONO (-1685 1835);
FORCEPROP 0 LASTPIN (-1675 1775) $PN 3
J 2
(-1685 1785);
DISPLAY 0.489362 (-1685 1785);
PAINT MONO (-1685 1785);
FORCEPROP 0 LASTPIN (-1675 1725) $PN 4
J 2
(-1685 1735);
DISPLAY 0.489362 (-1685 1735);
PAINT MONO (-1685 1735);
FORCEPROP 0 LASTPIN (-1675 1675) $PN 5
J 2
(-1685 1685);
DISPLAY 0.489362 (-1685 1685);
PAINT MONO (-1685 1685);
FORCEPROP 0 LASTPIN (-1675 1625) $PN 6
J 2
(-1685 1635);
DISPLAY 0.489362 (-1685 1635);
PAINT MONO (-1685 1635);
FORCEPROP 0 LASTPIN (-1675 1575) $PN 7
J 2
(-1685 1585);
DISPLAY 0.489362 (-1685 1585);
PAINT MONO (-1685 1585);
FORCEPROP 0 LASTPIN (-1675 1525) $PN 8
J 2
(-1685 1535);
DISPLAY 0.489362 (-1685 1535);
PAINT MONO (-1685 1535);
FORCEPROP 2 LAST VALUE CONN8_HBB1081-L200D-8H
J 0
(-1525 2075);
DISPLAY 0.489362 (-1525 2075);
PAINT SKYBLUE (-1525 2075);
FORCEPROP 1 LAST MATERIAL IO
J 0
(-1525 1937);
DISPLAY 0.489362 (-1525 1937);
PAINT SKYBLUE (-1525 1937);
FORCEPROP 2 LAST PART_TYPE THLF
J 0
(-1525 2125);
DISPLAY 1.021277 (-1525 2125);
FORCEPROP 2 LAST CDS_LIB pure_quanta
J 0
(-1475 1700);
DISPLAY INVISIBLE (-1475 1700);
FORCEPROP 1 LAST NEEDS_NO_SIZE TRUE
J 0
(-1475 1700);
DISPLAY 0.723404 (-1475 1700);
PAINT GREEN (-1475 1700);
DISPLAY INVISIBLE (-1475 1700);
FORCEPROP 1 LAST CDS_LMAN_SYM_OUTLINE -50,225,50,-225
J 0
(-1475 1700);
DISPLAY 0.468085 (-1475 1700);
PAINT GREEN (-1475 1700);
DISPLAY INVISIBLE (-1475 1700);
FORCEPROP 1 LAST PATH I41
J 0
(-1475 1700);
DISPLAY 0.723404 (-1475 1700);
PAINT GREEN (-1475 1700);
DISPLAY INVISIBLE (-1475 1700);
FORCEPROP 1 LAST PART_NUMBER DFHD08MS197
J 0
(-1525 2000);
DISPLAY 0.489362 (-1525 2000);
PAINT SKYBLUE (-1525 2000);
DISPLAY INVISIBLE (-1525 2000);
FORCEADD Q_CAP..1
(-1850 2075);
FORCEPROP 1 LAST LOCATION C20
J 0
(-2025 2175);
DISPLAY 0.489362 (-2025 2175);
PAINT SKYBLUE (-2025 2175);
FORCEPROP 0 LAST $SEC 1
J 0
(-2025 2225);
DISPLAY 0.680851 (-2025 2225);
PAINT MONO (-2025 2225);
DISPLAY INVISIBLE (-2025 2225);
FORCEPROP 0 LAST CDS_SEC 1
J 0
(-2025 2225);
DISPLAY 1.021277 (-2025 2225);
DISPLAY INVISIBLE (-2025 2225);
FORCEPROP 1 LASTPIN (-1850 2175) $PN 1
J 0
(-1840 2155);
DISPLAY 0.489362 (-1840 2155);
PAINT MONO (-1840 2155);
FORCEPROP 1 LASTPIN (-1850 1975) $PN 2
J 0
(-1840 1955);
DISPLAY 0.489362 (-1840 1955);
PAINT MONO (-1840 1955);
FORCEPROP 1 LAST PACK_TYPE C0402
J 0
(-2075 1925);
DISPLAY 0.489362 (-2075 1925);
PAINT SKYBLUE (-2075 1925);
FORCEPROP 1 LAST VOLTAGE 16V
J 0
(-2025 2075);
DISPLAY 0.489362 (-2025 2075);
PAINT SKYBLUE (-2025 2075);
FORCEPROP 1 LAST VALUE 0.1UF
J 0
(-2075 2125);
DISPLAY 0.489362 (-2075 2125);
PAINT SKYBLUE (-2075 2125);
FORCEPROP 1 LAST TOLERANCE 10%
J 0
(-2025 2025);
DISPLAY 0.489362 (-2025 2025);
PAINT SKYBLUE (-2025 2025);
FORCEPROP 1 LAST MATERIAL X7R
J 0
(-2025 1875);
DISPLAY 0.489362 (-2025 1875);
PAINT SKYBLUE (-2025 1875);
FORCEPROP 2 LAST CDS_LIB pure_quanta
J 0
(-1850 2075);
DISPLAY INVISIBLE (-1850 2075);
FORCEPROP 1 LAST PATH I42
J 0
(-1800 2225);
DISPLAY 0.978723 (-1800 2225);
PAINT WHITE (-1800 2225);
DISPLAY INVISIBLE (-1800 2225);
FORCEPROP 1 LAST PART_NUMBER CH4103K1B08
J 0
(-2200 1975);
DISPLAY 0.489362 (-2200 1975);
PAINT SKYBLUE (-2200 1975);
DISPLAY INVISIBLE (-2200 1975);
FORCEADD UNIVERSAL_POWER..1
R 2
(-1725 2375);
FORCEPROP 3 LASTPIN (-1725 2325) SIG_NAME P3V3_AUX\g
J 0
(-1715 2335);
DISPLAY 0.659574 (-1715 2335);
PAINT MONO (-1715 2335);
DISPLAY INVISIBLE (-1715 2335);
FORCEPROP 1 LAST HDL_POWER P3V3_AUX
J 1
(-1725 2425);
DISPLAY 0.489362 (-1725 2425);
PAINT GREEN (-1725 2425);
FORCEPROP 2 LAST CDS_LIB pure_quanta_power
J 0
(-1725 2375);
DISPLAY INVISIBLE (-1725 2375);
FORCEPROP 1 LAST PATH I43
J 2
(-1775 2400);
DISPLAY 0.872340 (-1775 2400);
PAINT AQUA (-1775 2400);
DISPLAY INVISIBLE (-1775 2400);
FORCEADD OFFPAGE..1
(-2875 5350);
FORCEPROP 2 LAST $XR0 81 
J 0
(-3126 5350);
DISPLAY 0.638298 (-3126 5350);
PAINT MONO (-3126 5350);
FORCEPROP 2 LAST CDS_LIB standard
J 0
(-2875 5350);
DISPLAY INVISIBLE (-2875 5350);
FORCEPROP 1 LAST OFFPAGE TRUE
J 0
(-2550 5225);
DISPLAY 0.872340 (-2550 5225);
PAINT GREEN (-2550 5225);
DISPLAY INVISIBLE (-2550 5225);
FORCEPROP 1 LAST COMMENT_BODY TRUE
J 0
(-2750 5250);
DISPLAY 0.872340 (-2750 5250);
PAINT GREEN (-2750 5250);
DISPLAY INVISIBLE (-2750 5250);
FORCEPROP 2 LAST PATH I44
J 0
(-3075 5400);
DISPLAY 0.680851 (-3075 5400);
DISPLAY INVISIBLE (-3075 5400);
FORCEADD Q_RES..1
(-3700 5700);
FORCEPROP 1 LAST LOCATION R1266
J 0
(-3750 5750);
DISPLAY 0.489362 (-3750 5750);
PAINT SKYBLUE (-3750 5750);
FORCEPROP 0 LAST $SEC 1
J 0
(-3750 5800);
DISPLAY 0.680851 (-3750 5800);
PAINT MONO (-3750 5800);
DISPLAY INVISIBLE (-3750 5800);
FORCEPROP 0 LAST CDS_SEC 1
J 0
(-3750 5800);
DISPLAY 0.680851 (-3750 5800);
DISPLAY INVISIBLE (-3750 5800);
FORCEPROP 1 LASTPIN (-3800 5700) $PN 1
J 0
(-3788 5712);
DISPLAY 0.489362 (-3788 5712);
PAINT MONO (-3788 5712);
FORCEPROP 1 LASTPIN (-3600 5700) $PN 2
J 0
(-3638 5712);
DISPLAY 0.489362 (-3638 5712);
PAINT MONO (-3638 5712);
FORCEPROP 1 LAST PACK_TYPE 0402LF
J 0
(-3475 5625);
DISPLAY 0.489362 (-3475 5625);
PAINT SKYBLUE (-3475 5625);
FORCEPROP 1 LAST WATTAGE 1/16W
J 2
(-3625 5625);
DISPLAY 0.489362 (-3625 5625);
PAINT SKYBLUE (-3625 5625);
FORCEPROP 1 LAST MATERIAL CHIP
J 0
(-3600 5625);
DISPLAY 0.489362 (-3600 5625);
PAINT SKYBLUE (-3600 5625);
FORCEPROP 1 LAST TOLERANCE 1%
J 0
(-3825 5625);
DISPLAY 0.489362 (-3825 5625);
PAINT SKYBLUE (-3825 5625);
FORCEPROP 1 LAST VALUE 200
J 2
(-3850 5625);
DISPLAY 0.489362 (-3850 5625);
PAINT SKYBLUE (-3850 5625);
FORCEPROP 2 LAST CDS_LIB pure_quanta
J 0
(-3700 5700);
DISPLAY INVISIBLE (-3700 5700);
FORCEPROP 1 LAST PATH I45
J 0
(-3750 5850);
DISPLAY 0.978723 (-3750 5850);
PAINT WHITE (-3750 5850);
DISPLAY INVISIBLE (-3750 5850);
FORCEPROP 1 LAST PART_NUMBER CS12002FB06
J 0
(-3325 5625);
DISPLAY 0.489362 (-3325 5625);
PAINT SKYBLUE (-3325 5625);
DISPLAY INVISIBLE (-3325 5625);
FORCEADD Q_RES..1
(-3700 6050);
FORCEPROP 1 LAST LOCATION R1194
J 0
(-3775 6125);
DISPLAY 0.489362 (-3775 6125);
PAINT SKYBLUE (-3775 6125);
FORCEPROP 0 LAST $SEC 1
J 0
(-3750 6150);
DISPLAY 0.680851 (-3750 6150);
PAINT MONO (-3750 6150);
DISPLAY INVISIBLE (-3750 6150);
FORCEPROP 0 LAST CDS_SEC 1
J 0
(-3750 6150);
DISPLAY 0.680851 (-3750 6150);
DISPLAY INVISIBLE (-3750 6150);
FORCEPROP 1 LASTPIN (-3800 6050) $PN 1
J 0
(-3788 6062);
DISPLAY 0.489362 (-3788 6062);
PAINT MONO (-3788 6062);
FORCEPROP 1 LASTPIN (-3600 6050) $PN 2
J 0
(-3638 6062);
DISPLAY 0.489362 (-3638 6062);
PAINT MONO (-3638 6062);
FORCEPROP 1 LAST WATTAGE 1/16W
J 2
(-3625 5975);
DISPLAY 0.489362 (-3625 5975);
PAINT SKYBLUE (-3625 5975);
FORCEPROP 1 LAST MATERIAL CHIP
J 0
(-3600 5975);
DISPLAY 0.489362 (-3600 5975);
PAINT SKYBLUE (-3600 5975);
FORCEPROP 1 LAST TOLERANCE 1%
J 0
(-3825 5975);
DISPLAY 0.489362 (-3825 5975);
PAINT SKYBLUE (-3825 5975);
FORCEPROP 1 LAST VALUE 200
J 2
(-3850 5975);
DISPLAY 0.489362 (-3850 5975);
PAINT SKYBLUE (-3850 5975);
FORCEPROP 1 LAST PACK_TYPE 0402LF
J 0
(-3475 5975);
DISPLAY 0.489362 (-3475 5975);
PAINT SKYBLUE (-3475 5975);
FORCEPROP 2 LAST CDS_LIB pure_quanta
J 0
(-3700 6050);
DISPLAY INVISIBLE (-3700 6050);
FORCEPROP 1 LAST PATH I46
J 0
(-3750 6200);
DISPLAY 0.978723 (-3750 6200);
PAINT WHITE (-3750 6200);
DISPLAY INVISIBLE (-3750 6200);
FORCEPROP 1 LAST PART_NUMBER CS12002FB06
J 0
(-3325 5975);
DISPLAY 0.489362 (-3325 5975);
PAINT SKYBLUE (-3325 5975);
DISPLAY INVISIBLE (-3325 5975);
FORCEADD UNIVERSAL_GND..1
(-2050 5175);
FORCEPROP 3 LASTPIN (-2050 5225) SIG_NAME GND\g
J 0
(-2040 5235);
DISPLAY 0.659574 (-2040 5235);
PAINT MONO (-2040 5235);
DISPLAY INVISIBLE (-2040 5235);
FORCEPROP 1 LAST HDL_POWER GND
J 1
(-2025 5100);
DISPLAY 0.489362 (-2025 5100);
PAINT GREEN (-2025 5100);
FORCEPROP 2 LAST BOM_COST MISC.
J 0
(-2025 5150);
DISPLAY 0.680851 (-2025 5150);
DISPLAY INVISIBLE (-2025 5150);
FORCEPROP 2 LAST CDS_LIB pure_quanta_power
J 0
(-2050 5175);
DISPLAY INVISIBLE (-2050 5175);
FORCEPROP 1 LAST PATH I47
J 0
(-1975 5175);
DISPLAY 0.872340 (-1975 5175);
PAINT AQUA (-1975 5175);
DISPLAY INVISIBLE (-1975 5175);
FORCEADD MOSFET_DUAL_6P..1
R 6
(-1675 5350);
FORCEPROP 1 LAST LOCATION Q28
J 0
(-1825 5564);
DISPLAY 0.489362 (-1825 5564);
PAINT SKYBLUE (-1825 5564);
FORCEPROP 0 LAST $SEC 1
J 0
(-1825 5675);
DISPLAY 0.680851 (-1825 5675);
PAINT MONO (-1825 5675);
DISPLAY INVISIBLE (-1825 5675);
FORCEPROP 0 LAST CDS_SEC 1
J 0
(-1825 5675);
DISPLAY 0.680851 (-1825 5675);
DISPLAY INVISIBLE (-1825 5675);
FORCEPROP 0 LASTPIN (-1975 5400) $PN 6
J 2
(-1985 5410);
DISPLAY 0.489362 (-1985 5410);
PAINT MONO (-1985 5410);
FORCEPROP 0 LASTPIN (-1375 5400) $PN 3
J 0
(-1365 5410);
DISPLAY 0.489362 (-1365 5410);
PAINT MONO (-1365 5410);
FORCEPROP 0 LASTPIN (-1975 5350) $PN 2
J 2
(-1985 5360);
DISPLAY 0.489362 (-1985 5360);
PAINT MONO (-1985 5360);
FORCEPROP 0 LASTPIN (-1375 5350) $PN 5
J 0
(-1365 5360);
DISPLAY 0.489362 (-1365 5360);
PAINT MONO (-1365 5360);
FORCEPROP 0 LASTPIN (-1975 5300) $PN 1
J 2
(-1985 5310);
DISPLAY 0.489362 (-1985 5310);
PAINT MONO (-1985 5310);
FORCEPROP 0 LASTPIN (-1375 5300) $PN 4
J 0
(-1365 5310);
DISPLAY 0.489362 (-1365 5310);
PAINT MONO (-1365 5310);
FORCEPROP 2 LAST PART_TYPE SMLF
J 0
(-1825 5464);
DISPLAY 0.680851 (-1825 5464);
FORCEPROP 1 LAST MATERIAL IC
J 0
(-1825 5650);
DISPLAY 0.489362 (-1825 5650);
PAINT SKYBLUE (-1825 5650);
FORCEPROP 2 LAST VALUE 2N7002KDW
J 0
(-1825 5523);
DISPLAY 0.489362 (-1825 5523);
PAINT SKYBLUE (-1825 5523);
FORCEPROP 2 LAST CDS_LIB pure_quanta
J 0
(-1675 5303);
DISPLAY INVISIBLE (-1675 5303);
FORCEPROP 1 LAST CDS_LMAN_SYM_OUTLINE -150,100,150,-100
J 0
(-1675 5328);
DISPLAY 0.468085 (-1675 5328);
PAINT GREEN (-1675 5328);
DISPLAY INVISIBLE (-1675 5328);
FORCEPROP 1 LAST NEEDS_NO_SIZE TRUE
J 0
(-1675 5329);
DISPLAY 0.468085 (-1675 5329);
PAINT GREEN (-1675 5329);
DISPLAY INVISIBLE (-1675 5329);
FORCEPROP 1 LAST PATH I48
J 0
(-1675 5350);
DISPLAY 0.723404 (-1675 5350);
PAINT GREEN (-1675 5350);
DISPLAY INVISIBLE (-1675 5350);
FORCEPROP 1 LAST PART_NUMBER BAM70020047
J 0
(-1825 5606);
DISPLAY 0.489362 (-1825 5606);
PAINT SKYBLUE (-1825 5606);
DISPLAY INVISIBLE (-1825 5606);
FORCEADD Q_RES..1
(-7625 1700);
FORCEPROP 1 LAST LOCATION R1303
J 0
(-7825 1700);
DISPLAY 0.489362 (-7825 1700);
PAINT SKYBLUE (-7825 1700);
FORCEPROP 0 LAST $SEC 1
J 0
(-7475 1750);
DISPLAY 0.680851 (-7475 1750);
PAINT MONO (-7475 1750);
DISPLAY INVISIBLE (-7475 1750);
FORCEPROP 0 LAST CDS_SEC 1
J 0
(-7475 1750);
DISPLAY 0.680851 (-7475 1750);
DISPLAY INVISIBLE (-7475 1750);
FORCEPROP 1 LASTPIN (-7725 1700) $PN 1
J 0
(-7713 1712);
DISPLAY 0.489362 (-7713 1712);
PAINT MONO (-7713 1712);
FORCEPROP 1 LASTPIN (-7525 1700) $PN 2
J 0
(-7563 1712);
DISPLAY 0.489362 (-7563 1712);
PAINT MONO (-7563 1712);
FORCEPROP 1 LAST VALUE 1K
J 0
(-7425 1700);
DISPLAY 0.489362 (-7425 1700);
PAINT SKYBLUE (-7425 1700);
FORCEPROP 2 LAST CDS_LIB pure_quanta
J 0
(-7625 1700);
DISPLAY INVISIBLE (-7625 1700);
FORCEPROP 1 LAST PACK_TYPE 0402LF
J 0
(-7375 1550);
DISPLAY 0.510638 (-7375 1550);
PAINT SKYBLUE (-7375 1550);
DISPLAY INVISIBLE (-7375 1550);
FORCEPROP 1 LAST MATERIAL CHIP
J 0
(-7525 1675);
DISPLAY 0.489362 (-7525 1675);
PAINT SKYBLUE (-7525 1675);
DISPLAY INVISIBLE (-7525 1675);
FORCEPROP 1 LAST WATTAGE 1/16W
J 2
(-7650 1550);
DISPLAY 0.510638 (-7650 1550);
PAINT SKYBLUE (-7650 1550);
DISPLAY INVISIBLE (-7650 1550);
FORCEPROP 1 LAST TOLERANCE 1%
J 0
(-7500 1700);
DISPLAY 0.510638 (-7500 1700);
PAINT SKYBLUE (-7500 1700);
DISPLAY INVISIBLE (-7500 1700);
FORCEPROP 1 LAST PATH I5
J 0
(-7675 1850);
DISPLAY 0.978723 (-7675 1850);
PAINT WHITE (-7675 1850);
DISPLAY INVISIBLE (-7675 1850);
FORCEPROP 1 LAST PART_NUMBER CS21002FB06
J 0
(-7675 1800);
DISPLAY 0.510638 (-7675 1800);
PAINT SKYBLUE (-7675 1800);
DISPLAY INVISIBLE (-7675 1800);
FORCEADD UNIVERSAL_GND..1
(-1275 5175);
FORCEPROP 3 LASTPIN (-1275 5225) SIG_NAME GND\g
J 0
(-1265 5235);
DISPLAY 0.659574 (-1265 5235);
PAINT MONO (-1265 5235);
DISPLAY INVISIBLE (-1265 5235);
FORCEPROP 1 LAST HDL_POWER GND
J 1
(-1250 5100);
DISPLAY 0.489362 (-1250 5100);
PAINT GREEN (-1250 5100);
FORCEPROP 2 LAST BOM_COST MISC.
J 0
(-1250 5150);
DISPLAY 0.680851 (-1250 5150);
DISPLAY INVISIBLE (-1250 5150);
FORCEPROP 2 LAST CDS_LIB pure_quanta_power
J 0
(-1275 5175);
DISPLAY INVISIBLE (-1275 5175);
FORCEPROP 1 LAST PATH I51
J 0
(-1200 5175);
DISPLAY 0.872340 (-1200 5175);
PAINT AQUA (-1200 5175);
DISPLAY INVISIBLE (-1200 5175);
FORCEADD OFFPAGE..1
R 2
(-650 5350);
FORCEPROP 2 LAST $XR0 81 
J 0
(-464 5350);
DISPLAY 0.638298 (-464 5350);
PAINT MONO (-464 5350);
FORCEPROP 2 LAST CDS_LIB standard
J 0
(-650 5350);
DISPLAY INVISIBLE (-650 5350);
FORCEPROP 1 LAST OFFPAGE TRUE
J 2
(-975 5225);
DISPLAY 0.872340 (-975 5225);
PAINT GREEN (-975 5225);
DISPLAY INVISIBLE (-975 5225);
FORCEPROP 1 LAST COMMENT_BODY TRUE
J 2
(-775 5250);
DISPLAY 0.872340 (-775 5250);
PAINT GREEN (-775 5250);
DISPLAY INVISIBLE (-775 5250);
FORCEPROP 2 LAST PATH I52
J 0
(-450 5400);
DISPLAY 0.680851 (-450 5400);
DISPLAY INVISIBLE (-450 5400);
FORCEADD Q_RES..1
(-7550 1550);
FORCEPROP 1 LAST LOCATION R6074
J 0
(-7450 1550);
DISPLAY 0.489362 (-7450 1550);
PAINT SKYBLUE (-7450 1550);
FORCEPROP 0 LAST $SEC 1
J 0
(-7450 1600);
DISPLAY 0.680851 (-7450 1600);
PAINT MONO (-7450 1600);
DISPLAY INVISIBLE (-7450 1600);
FORCEPROP 0 LAST CDS_SEC 1
J 0
(-7450 1600);
DISPLAY 0.680851 (-7450 1600);
DISPLAY INVISIBLE (-7450 1600);
FORCEPROP 1 LASTPIN (-7650 1550) $PN 1
J 0
(-7638 1562);
DISPLAY 0.489362 (-7638 1562);
PAINT MONO (-7638 1562);
FORCEPROP 1 LASTPIN (-7450 1550) $PN 2
J 0
(-7488 1562);
DISPLAY 0.489362 (-7488 1562);
PAINT MONO (-7488 1562);
FORCEPROP 1 LAST VALUE 0
J 2
(-7675 1550);
DISPLAY 0.489362 (-7675 1550);
PAINT SKYBLUE (-7675 1550);
FORCEPROP 1 LAST PACK_TYPE 0402LF
J 2
(-7375 1475);
DISPLAY 0.489362 (-7375 1475);
PAINT SKYBLUE (-7375 1475);
DISPLAY INVISIBLE (-7375 1475);
FORCEPROP 1 LAST TOLERANCE 5%
J 0
(-7675 1525);
DISPLAY 0.489362 (-7675 1525);
PAINT SKYBLUE (-7675 1525);
DISPLAY INVISIBLE (-7675 1525);
FORCEPROP 1 LAST MATERIAL CHIP
J 2
(-7375 1525);
DISPLAY 0.489362 (-7375 1525);
PAINT SKYBLUE (-7375 1525);
DISPLAY INVISIBLE (-7375 1525);
FORCEPROP 1 LAST WATTAGE 1/16W
J 2
(-7625 1475);
DISPLAY 0.489362 (-7625 1475);
PAINT SKYBLUE (-7625 1475);
DISPLAY INVISIBLE (-7625 1475);
FORCEPROP 2 LAST BOM_COST MEM
J 2
(-7525 1700);
DISPLAY 0.744681 (-7525 1700);
PAINT WHITE (-7525 1700);
DISPLAY INVISIBLE (-7525 1700);
FORCEPROP 2 LAST CDS_LIB pure_quanta
J 0
(-7550 1550);
DISPLAY INVISIBLE (-7550 1550);
FORCEPROP 1 LAST PATH I53
J 0
(-7600 1700);
DISPLAY 0.978723 (-7600 1700);
PAINT WHITE (-7600 1700);
DISPLAY INVISIBLE (-7600 1700);
FORCEPROP 1 LAST PART_NUMBER CS00002JB13
J 2
(-7450 1600);
DISPLAY 0.489362 (-7450 1600);
PAINT SKYBLUE (-7450 1600);
DISPLAY INVISIBLE (-7450 1600);
FORCEADD OFFPAGE..2
(-6725 1550);
FORCEPROP 2 LAST $XR0 82 
J 0
(-6536 1550);
DISPLAY 0.638298 (-6536 1550);
PAINT MONO (-6536 1550);
FORCEPROP 2 LAST CDS_LIB standard
J 0
(-6725 1550);
DISPLAY INVISIBLE (-6725 1550);
FORCEPROP 1 LAST OFFPAGE TRUE
J 0
(-6400 1425);
DISPLAY 0.872340 (-6400 1425);
PAINT GREEN (-6400 1425);
DISPLAY INVISIBLE (-6400 1425);
FORCEPROP 1 LAST COMMENT_BODY TRUE
J 0
(-6770 1455);
DISPLAY 0.872340 (-6770 1455);
PAINT GREEN (-6770 1455);
DISPLAY INVISIBLE (-6770 1455);
FORCEPROP 2 LAST PATH I54
J 0
(-6525 1600);
DISPLAY 0.680851 (-6525 1600);
DISPLAY INVISIBLE (-6525 1600);
FORCEADD OFFPAGE..1
(-8375 1550);
FORCEPROP 2 LAST $XR0 236 
J 0
(-8657 1550);
DISPLAY 0.638298 (-8657 1550);
PAINT MONO (-8657 1550);
FORCEPROP 2 LAST CDS_LIB standard
J 0
(-8375 1550);
DISPLAY INVISIBLE (-8375 1550);
FORCEPROP 1 LAST OFFPAGE TRUE
J 0
(-8045 1420);
PAINT GREEN (-8045 1420);
DISPLAY INVISIBLE (-8045 1420);
FORCEPROP 1 LAST COMMENT_BODY TRUE
J 0
(-8245 1450);
DISPLAY 1.106383 (-8245 1450);
PAINT PEACH (-8245 1450);
DISPLAY INVISIBLE (-8245 1450);
FORCEPROP 2 LAST PATH I55
J 0
(-8325 1625);
DISPLAY 0.680851 (-8325 1625);
DISPLAY INVISIBLE (-8325 1625);
FORCEADD OFFPAGE..2
(-6725 1425);
FORCEPROP 2 LAST $XR0 82 
J 0
(-6536 1425);
DISPLAY 0.638298 (-6536 1425);
PAINT MONO (-6536 1425);
FORCEPROP 2 LAST CDS_LIB standard
J 0
(-6725 1425);
DISPLAY INVISIBLE (-6725 1425);
FORCEPROP 1 LAST OFFPAGE TRUE
J 0
(-6400 1300);
DISPLAY 0.872340 (-6400 1300);
PAINT GREEN (-6400 1300);
DISPLAY INVISIBLE (-6400 1300);
FORCEPROP 1 LAST COMMENT_BODY TRUE
J 0
(-6770 1330);
DISPLAY 0.872340 (-6770 1330);
PAINT GREEN (-6770 1330);
DISPLAY INVISIBLE (-6770 1330);
FORCEPROP 2 LAST PATH I56
J 0
(-6550 1500);
DISPLAY 0.680851 (-6550 1500);
DISPLAY INVISIBLE (-6550 1500);
FORCEADD Q_RES..1
(-7550 1425);
FORCEPROP 1 LAST LOCATION R6075
J 0
(-7450 1425);
DISPLAY 0.489362 (-7450 1425);
PAINT SKYBLUE (-7450 1425);
FORCEPROP 0 LAST $SEC 1
J 0
(-7450 1475);
DISPLAY 0.680851 (-7450 1475);
PAINT MONO (-7450 1475);
DISPLAY INVISIBLE (-7450 1475);
FORCEPROP 0 LAST CDS_SEC 1
J 0
(-7450 1475);
DISPLAY 0.680851 (-7450 1475);
DISPLAY INVISIBLE (-7450 1475);
FORCEPROP 1 LASTPIN (-7650 1425) $PN 1
J 0
(-7638 1437);
DISPLAY 0.489362 (-7638 1437);
PAINT MONO (-7638 1437);
FORCEPROP 1 LASTPIN (-7450 1425) $PN 2
J 0
(-7488 1437);
DISPLAY 0.489362 (-7488 1437);
PAINT MONO (-7488 1437);
FORCEPROP 1 LAST VALUE 0
J 2
(-7675 1425);
DISPLAY 0.489362 (-7675 1425);
PAINT SKYBLUE (-7675 1425);
FORCEPROP 1 LAST PACK_TYPE 0402LF
J 2
(-7375 1350);
DISPLAY 0.489362 (-7375 1350);
PAINT SKYBLUE (-7375 1350);
DISPLAY INVISIBLE (-7375 1350);
FORCEPROP 1 LAST TOLERANCE 5%
J 0
(-7675 1400);
DISPLAY 0.489362 (-7675 1400);
PAINT SKYBLUE (-7675 1400);
DISPLAY INVISIBLE (-7675 1400);
FORCEPROP 1 LAST MATERIAL CHIP
J 2
(-7375 1400);
DISPLAY 0.489362 (-7375 1400);
PAINT SKYBLUE (-7375 1400);
DISPLAY INVISIBLE (-7375 1400);
FORCEPROP 1 LAST WATTAGE 1/16W
J 2
(-7625 1350);
DISPLAY 0.489362 (-7625 1350);
PAINT SKYBLUE (-7625 1350);
DISPLAY INVISIBLE (-7625 1350);
FORCEPROP 2 LAST BOM_COST MEM
J 2
(-7525 1575);
DISPLAY 0.744681 (-7525 1575);
PAINT WHITE (-7525 1575);
DISPLAY INVISIBLE (-7525 1575);
FORCEPROP 2 LAST CDS_LIB pure_quanta
J 0
(-7550 1425);
DISPLAY INVISIBLE (-7550 1425);
FORCEPROP 1 LAST PATH I57
J 0
(-7600 1575);
DISPLAY 0.978723 (-7600 1575);
PAINT WHITE (-7600 1575);
DISPLAY INVISIBLE (-7600 1575);
FORCEPROP 1 LAST PART_NUMBER CS00002JB13
J 2
(-7450 1475);
DISPLAY 0.489362 (-7450 1475);
PAINT SKYBLUE (-7450 1475);
DISPLAY INVISIBLE (-7450 1475);
FORCEADD OFFPAGE..1
(-8375 1425);
FORCEPROP 2 LAST $XR1 150 
J 0
(-8777 1425);
DISPLAY 0.638298 (-8777 1425);
PAINT MONO (-8777 1425);
FORCEPROP 2 LAST $XR0 144 
J 0
(-8657 1425);
DISPLAY 0.638298 (-8657 1425);
PAINT MONO (-8657 1425);
FORCEPROP 2 LAST CDS_LIB standard
J 0
(-8375 1425);
DISPLAY INVISIBLE (-8375 1425);
FORCEPROP 1 LAST OFFPAGE TRUE
J 0
(-8045 1295);
PAINT GREEN (-8045 1295);
DISPLAY INVISIBLE (-8045 1295);
FORCEPROP 1 LAST COMMENT_BODY TRUE
J 0
(-8245 1325);
DISPLAY 1.106383 (-8245 1325);
PAINT PEACH (-8245 1325);
DISPLAY INVISIBLE (-8245 1325);
FORCEPROP 2 LAST PATH I58
J 0
(-8325 1500);
DISPLAY 0.680851 (-8325 1500);
DISPLAY INVISIBLE (-8325 1500);
FORCEADD OFFPAGE..1
(-8375 1300);
FORCEPROP 2 LAST $XR2 270 
J 0
(-8867 1300);
DISPLAY 0.638298 (-8867 1300);
PAINT MONO (-8867 1300);
FORCEPROP 2 LAST $XR1 81 
J 0
(-8747 1300);
DISPLAY 0.638298 (-8747 1300);
PAINT MONO (-8747 1300);
FORCEPROP 2 LAST $XR0 190 
J 0
(-8657 1300);
DISPLAY 0.638298 (-8657 1300);
PAINT MONO (-8657 1300);
FORCEPROP 2 LAST CDS_LIB standard
J 0
(-8375 1300);
DISPLAY INVISIBLE (-8375 1300);
FORCEPROP 1 LAST OFFPAGE TRUE
J 0
(-8045 1170);
PAINT GREEN (-8045 1170);
DISPLAY INVISIBLE (-8045 1170);
FORCEPROP 1 LAST COMMENT_BODY TRUE
J 0
(-8245 1200);
DISPLAY 1.106383 (-8245 1200);
PAINT PEACH (-8245 1200);
DISPLAY INVISIBLE (-8245 1200);
FORCEPROP 2 LAST PATH I59
J 0
(-8325 1375);
DISPLAY 0.680851 (-8325 1375);
DISPLAY INVISIBLE (-8325 1375);
FORCEADD Q_RES..1
(-7625 1925);
FORCEPROP 1 LAST LOCATION R1036
J 0
(-7825 1925);
DISPLAY 0.489362 (-7825 1925);
PAINT SKYBLUE (-7825 1925);
FORCEPROP 2 LAST $SEC 1
J 0
(-7675 2125);
DISPLAY 0.680851 (-7675 2125);
PAINT MONO (-7675 2125);
DISPLAY INVISIBLE (-7675 2125);
FORCEPROP 2 LAST CDS_SEC 1
J 0
(-7675 2125);
DISPLAY 0.680851 (-7675 2125);
DISPLAY INVISIBLE (-7675 2125);
FORCEPROP 1 LASTPIN (-7725 1925) $PN 1
J 0
(-7713 1937);
DISPLAY 0.489362 (-7713 1937);
PAINT MONO (-7713 1937);
FORCEPROP 1 LASTPIN (-7525 1925) $PN 2
J 0
(-7563 1937);
DISPLAY 0.489362 (-7563 1937);
PAINT MONO (-7563 1937);
FORCEPROP 1 LAST VALUE 0
J 2
(-7400 1925);
DISPLAY 0.489362 (-7400 1925);
PAINT SKYBLUE (-7400 1925);
FORCEPROP 1 LAST MATERIAL CHIP
J 0
(-7350 1925);
DISPLAY 0.489362 (-7350 1925);
PAINT SKYBLUE (-7350 1925);
FORCEPROP 2 LAST CDS_LIB pure_quanta
J 0
(-7625 1925);
DISPLAY INVISIBLE (-7625 1925);
FORCEPROP 2 LAST BOM_COST OCP3.0 
J 0
(-7550 2025);
DISPLAY 0.680851 (-7550 2025);
DISPLAY INVISIBLE (-7550 2025);
FORCEPROP 1 LAST WATTAGE 1/16W
J 2
(-7650 1825);
DISPLAY 0.489362 (-7650 1825);
PAINT SKYBLUE (-7650 1825);
DISPLAY INVISIBLE (-7650 1825);
FORCEPROP 1 LAST TOLERANCE 5%
J 0
(-7625 1875);
DISPLAY 0.489362 (-7625 1875);
PAINT SKYBLUE (-7625 1875);
DISPLAY INVISIBLE (-7625 1875);
FORCEPROP 1 LAST PACK_TYPE 0402LF
J 0
(-7550 1875);
DISPLAY 0.489362 (-7550 1875);
PAINT SKYBLUE (-7550 1875);
DISPLAY INVISIBLE (-7550 1875);
FORCEPROP 1 LAST PATH I6
J 0
(-7675 2075);
DISPLAY 0.978723 (-7675 2075);
PAINT WHITE (-7675 2075);
DISPLAY INVISIBLE (-7675 2075);
FORCEPROP 1 LAST PART_NUMBER CS00002JB13
J 0
(-7550 1975);
DISPLAY 0.489362 (-7550 1975);
PAINT SKYBLUE (-7550 1975);
DISPLAY INVISIBLE (-7550 1975);
FORCEADD OFFPAGE..2
(-6725 1300);
FORCEPROP 2 LAST $XR0 242 
J 0
(-6536 1300);
DISPLAY 0.638298 (-6536 1300);
PAINT MONO (-6536 1300);
FORCEPROP 2 LAST CDS_LIB standard
J 0
(-6725 1300);
DISPLAY INVISIBLE (-6725 1300);
FORCEPROP 1 LAST OFFPAGE TRUE
J 0
(-6400 1175);
DISPLAY 0.872340 (-6400 1175);
PAINT GREEN (-6400 1175);
DISPLAY INVISIBLE (-6400 1175);
FORCEPROP 1 LAST COMMENT_BODY TRUE
J 0
(-6770 1205);
DISPLAY 0.872340 (-6770 1205);
PAINT GREEN (-6770 1205);
DISPLAY INVISIBLE (-6770 1205);
FORCEPROP 2 LAST PATH I60
J 0
(-6550 1375);
DISPLAY 0.680851 (-6550 1375);
DISPLAY INVISIBLE (-6550 1375);
FORCEADD Q_RES..1
(-7550 1300);
FORCEPROP 1 LAST LOCATION R6078
J 0
(-7450 1300);
DISPLAY 0.489362 (-7450 1300);
PAINT SKYBLUE (-7450 1300);
FORCEPROP 0 LAST $SEC 1
J 0
(-7450 1350);
DISPLAY 0.680851 (-7450 1350);
PAINT MONO (-7450 1350);
DISPLAY INVISIBLE (-7450 1350);
FORCEPROP 0 LAST CDS_SEC 1
J 0
(-7450 1350);
DISPLAY 0.680851 (-7450 1350);
DISPLAY INVISIBLE (-7450 1350);
FORCEPROP 1 LASTPIN (-7650 1300) $PN 1
J 0
(-7638 1312);
DISPLAY 0.489362 (-7638 1312);
PAINT MONO (-7638 1312);
FORCEPROP 1 LASTPIN (-7450 1300) $PN 2
J 0
(-7488 1312);
DISPLAY 0.489362 (-7488 1312);
PAINT MONO (-7488 1312);
FORCEPROP 1 LAST VALUE 0
J 2
(-7675 1300);
DISPLAY 0.489362 (-7675 1300);
PAINT SKYBLUE (-7675 1300);
FORCEPROP 1 LAST PACK_TYPE 0402LF
J 2
(-7375 1225);
DISPLAY 0.489362 (-7375 1225);
PAINT SKYBLUE (-7375 1225);
DISPLAY INVISIBLE (-7375 1225);
FORCEPROP 1 LAST TOLERANCE 5%
J 0
(-7675 1275);
DISPLAY 0.489362 (-7675 1275);
PAINT SKYBLUE (-7675 1275);
DISPLAY INVISIBLE (-7675 1275);
FORCEPROP 1 LAST MATERIAL CHIP
J 2
(-7375 1275);
DISPLAY 0.489362 (-7375 1275);
PAINT SKYBLUE (-7375 1275);
DISPLAY INVISIBLE (-7375 1275);
FORCEPROP 1 LAST WATTAGE 1/16W
J 2
(-7625 1225);
DISPLAY 0.489362 (-7625 1225);
PAINT SKYBLUE (-7625 1225);
DISPLAY INVISIBLE (-7625 1225);
FORCEPROP 2 LAST BOM_COST MEM
J 2
(-7525 1450);
DISPLAY 0.744681 (-7525 1450);
PAINT WHITE (-7525 1450);
DISPLAY INVISIBLE (-7525 1450);
FORCEPROP 2 LAST CDS_LIB pure_quanta
J 0
(-7550 1300);
DISPLAY INVISIBLE (-7550 1300);
FORCEPROP 1 LAST PATH I61
J 0
(-7600 1450);
DISPLAY 0.978723 (-7600 1450);
PAINT WHITE (-7600 1450);
DISPLAY INVISIBLE (-7600 1450);
FORCEPROP 1 LAST PART_NUMBER CS00002JB13
J 2
(-7450 1350);
DISPLAY 0.489362 (-7450 1350);
PAINT SKYBLUE (-7450 1350);
DISPLAY INVISIBLE (-7450 1350);
FORCEADD OFFPAGE..1
(-4350 3525);
FORCEPROP 2 LAST $XR1 190 
J 0
(-4722 3525);
DISPLAY 0.638298 (-4722 3525);
PAINT MONO (-4722 3525);
FORCEPROP 2 LAST $XR0 189 
J 0
(-4602 3525);
DISPLAY 0.638298 (-4602 3525);
PAINT MONO (-4602 3525);
FORCEPROP 2 LAST CDS_LIB standard
J 0
(-4350 3525);
DISPLAY INVISIBLE (-4350 3525);
FORCEPROP 1 LAST OFFPAGE TRUE
J 0
(-4025 3400);
DISPLAY 0.872340 (-4025 3400);
DISPLAY INVISIBLE (-4025 3400);
FORCEPROP 1 LAST COMMENT_BODY TRUE
J 0
(-4225 3425);
DISPLAY 1.170213 (-4225 3425);
PAINT GREEN (-4225 3425);
DISPLAY INVISIBLE (-4225 3425);
FORCEPROP 2 LAST PATH I62
J 0
(-4625 3575);
DISPLAY 0.680851 (-4625 3575);
DISPLAY INVISIBLE (-4625 3575);
FORCEADD Q_RES..2
(-4225 3900);
FORCEPROP 1 LAST LOCATION R2343
J 0
(-4180 4025);
DISPLAY 0.978723 (-4180 4025);
FORCEPROP 0 LAST $SEC 1
J 0
(-4175 4075);
DISPLAY 0.680851 (-4175 4075);
PAINT MONO (-4175 4075);
DISPLAY INVISIBLE (-4175 4075);
FORCEPROP 0 LAST CDS_SEC 1
J 0
(-4175 4075);
DISPLAY 1.021277 (-4175 4075);
DISPLAY INVISIBLE (-4175 4075);
FORCEPROP 1 LASTPIN (-4225 4000) $PN 1
J 0
(-4220 3962);
DISPLAY 0.787234 (-4220 3962);
PAINT MONO (-4220 3962);
FORCEPROP 1 LASTPIN (-4225 3800) $PN 2
J 0
(-4220 3810);
DISPLAY 0.787234 (-4220 3810);
PAINT MONO (-4220 3810);
FORCEPROP 1 LAST PACK_TYPE 0402LF
J 0
(-4185 3725);
DISPLAY 0.638298 (-4185 3725);
FORCEPROP 1 LAST VALUE 10K
J 0
(-4180 3975);
DISPLAY 0.638298 (-4180 3975);
FORCEPROP 1 LAST TOLERANCE 1%
J 0
(-4180 3925);
DISPLAY 0.638298 (-4180 3925);
FORCEPROP 1 LAST WATTAGE 1/16W
J 0
(-4185 3875);
DISPLAY 0.638298 (-4185 3875);
FORCEPROP 1 LAST MATERIAL EMPTY
J 0
(-4185 3825);
DISPLAY 0.638298 (-4185 3825);
PAINT RED (-4185 3825);
FORCEPROP 2 LAST CDS_LIB pure_quanta
J 0
(-4225 3900);
DISPLAY INVISIBLE (-4225 3900);
FORCEPROP 1 LAST PATH I63
J 0
(-4175 4075);
DISPLAY 0.978723 (-4175 4075);
PAINT WHITE (-4175 4075);
DISPLAY INVISIBLE (-4175 4075);
FORCEPROP 1 LAST PART_NUMBER CS31002FB08
J 0
(-4185 3775);
DISPLAY 0.638298 (-4185 3775);
DISPLAY INVISIBLE (-4185 3775);
FORCEADD UNIVERSAL_POWER..1
(-4225 4150);
FORCEPROP 3 LASTPIN (-4225 4100) SIG_NAME P5V_AUX_VCC\g
J 0
(-4215 4110);
DISPLAY 0.659574 (-4215 4110);
PAINT MONO (-4215 4110);
DISPLAY INVISIBLE (-4215 4110);
FORCEPROP 1 LAST HDL_POWER P5V_AUX_VCC
J 1
(-4225 4200);
DISPLAY 0.872340 (-4225 4200);
PAINT GREEN (-4225 4200);
FORCEPROP 2 LAST CDS_LIB pure_quanta_power
J 0
(-4225 4150);
DISPLAY INVISIBLE (-4225 4150);
FORCEPROP 1 LAST PATH I64
J 0
(-4175 4175);
DISPLAY 0.872340 (-4175 4175);
PAINT AQUA (-4175 4175);
DISPLAY INVISIBLE (-4175 4175);
FORCEADD MOSFET_NCH_DUAL..1
(-3300 3575);
FORCEPROP 1 LAST LOCATION Q50
J 0
(-3149 3549);
DISPLAY 0.723404 (-3149 3549);
PAINT GREEN (-3149 3549);
FORCEPROP 0 LAST $SEC 1
J 0
(-3125 3700);
DISPLAY 0.680851 (-3125 3700);
PAINT MONO (-3125 3700);
DISPLAY INVISIBLE (-3125 3700);
FORCEPROP 0 LAST CDS_SEC 1
J 0
(-3125 3700);
DISPLAY 1.021277 (-3125 3700);
DISPLAY INVISIBLE (-3125 3700);
FORCEPROP 0 LASTPIN (-3250 3775) $PN 6
R 1
J 0
(-3260 3785);
DISPLAY 0.680851 (-3260 3785);
PAINT MONO (-3260 3785);
FORCEPROP 0 LASTPIN (-3500 3525) $PN 2
J 2
(-3510 3535);
DISPLAY 0.680851 (-3510 3535);
PAINT MONO (-3510 3535);
FORCEPROP 0 LASTPIN (-3250 3375) $PN 1
R 1
J 2
(-3260 3365);
DISPLAY 0.680851 (-3260 3365);
PAINT MONO (-3260 3365);
FORCEPROP 2 LAST PART_TYPE SMLF
J 0
(-3125 3650);
DISPLAY 0.680851 (-3125 3650);
FORCEPROP 1 LAST MATERIAL IC
J 0
(-3149 3424);
DISPLAY 0.723404 (-3149 3424);
PAINT GREEN (-3149 3424);
FORCEPROP 2 LAST VALUE PJT138K
J 0
(-3125 3600);
DISPLAY 0.680851 (-3125 3600);
FORCEPROP 2 LAST CDS_LIB pure_quanta
J 0
(-3300 3575);
DISPLAY INVISIBLE (-3300 3575);
FORCEPROP 1 LAST CDS_LMAN_SYM_OUTLINE -150,150,150,-150
J 0
(-3300 3575);
DISPLAY 0.468085 (-3300 3575);
PAINT GREEN (-3300 3575);
DISPLAY INVISIBLE (-3300 3575);
FORCEPROP 1 LAST NEEDS_NO_SIZE TRUE
J 0
(-3300 3574);
DISPLAY 0.468085 (-3300 3574);
PAINT GREEN (-3300 3574);
DISPLAY INVISIBLE (-3300 3574);
FORCEPROP 1 LAST PATH I65
J 0
(-3300 3575);
DISPLAY 0.723404 (-3300 3575);
PAINT GREEN (-3300 3575);
DISPLAY INVISIBLE (-3300 3575);
FORCEPROP 1 LAST PART_NUMBER BAM138K0003
J 0
(-3149 3489);
DISPLAY 0.723404 (-3149 3489);
PAINT GREEN (-3149 3489);
DISPLAY INVISIBLE (-3149 3489);
FORCEADD UNIVERSAL_GND..1
(-3250 3275);
FORCEPROP 3 LASTPIN (-3250 3325) SIG_NAME GND\g
J 0
(-3240 3335);
DISPLAY 0.659574 (-3240 3335);
PAINT MONO (-3240 3335);
DISPLAY INVISIBLE (-3240 3335);
FORCEPROP 2 LAST CDS_LIB pure_quanta_power
J 0
(-3250 3275);
DISPLAY INVISIBLE (-3250 3275);
FORCEPROP 1 LAST HDL_POWER GND
J 1
(-3225 3200);
DISPLAY 0.872340 (-3225 3200);
PAINT GREEN (-3225 3200);
DISPLAY INVISIBLE (-3225 3200);
FORCEPROP 1 LAST PATH I66
J 0
(-3175 3275);
DISPLAY 0.872340 (-3175 3275);
PAINT AQUA (-3175 3275);
DISPLAY INVISIBLE (-3175 3275);
FORCEADD Q_RES..2
(-3250 4100);
FORCEPROP 1 LAST LOCATION R2344
J 0
(-3205 4225);
DISPLAY 0.978723 (-3205 4225);
FORCEPROP 0 LAST $SEC 1
J 0
(-3200 4275);
DISPLAY 0.680851 (-3200 4275);
PAINT MONO (-3200 4275);
DISPLAY INVISIBLE (-3200 4275);
FORCEPROP 0 LAST CDS_SEC 1
J 0
(-3200 4275);
DISPLAY 1.021277 (-3200 4275);
DISPLAY INVISIBLE (-3200 4275);
FORCEPROP 1 LASTPIN (-3250 4200) $PN 1
J 0
(-3245 4162);
DISPLAY 0.787234 (-3245 4162);
PAINT MONO (-3245 4162);
FORCEPROP 1 LASTPIN (-3250 4000) $PN 2
J 0
(-3245 4010);
DISPLAY 0.787234 (-3245 4010);
PAINT MONO (-3245 4010);
FORCEPROP 1 LAST PACK_TYPE 0402LF
J 0
(-3210 3975);
DISPLAY 0.510638 (-3210 3975);
FORCEPROP 1 LAST VALUE 4.7K
J 0
(-3205 4175);
DISPLAY 0.510638 (-3205 4175);
FORCEPROP 1 LAST TOLERANCE 5%
J 0
(-3205 4125);
DISPLAY 0.510638 (-3205 4125);
FORCEPROP 1 LAST MATERIAL CHIP
J 0
(-3210 4025);
DISPLAY 0.510638 (-3210 4025);
FORCEPROP 1 LAST WATTAGE 1/16W
J 0
(-3210 4075);
DISPLAY 0.510638 (-3210 4075);
FORCEPROP 2 LAST CDS_LIB pure_quanta
J 0
(-3250 4100);
DISPLAY INVISIBLE (-3250 4100);
FORCEPROP 1 LAST PATH I67
J 0
(-3200 4275);
DISPLAY 0.978723 (-3200 4275);
PAINT WHITE (-3200 4275);
DISPLAY INVISIBLE (-3200 4275);
FORCEPROP 1 LAST PART_NUMBER CS24702JB10
J 0
(-3210 3925);
DISPLAY 0.510638 (-3210 3925);
DISPLAY INVISIBLE (-3210 3925);
FORCEADD UNIVERSAL_POWER..1
(-3250 4350);
FORCEPROP 3 LASTPIN (-3250 4300) SIG_NAME P3V3_AUX\g
J 0
(-3240 4310);
DISPLAY 0.659574 (-3240 4310);
PAINT MONO (-3240 4310);
DISPLAY INVISIBLE (-3240 4310);
FORCEPROP 1 LAST HDL_POWER P3V3_AUX
J 1
(-3250 4400);
DISPLAY 0.872340 (-3250 4400);
PAINT GREEN (-3250 4400);
FORCEPROP 2 LAST CDS_LIB pure_quanta_power
J 0
(-3250 4350);
PAINT MONO (-3250 4350);
DISPLAY INVISIBLE (-3250 4350);
FORCEPROP 1 LAST PATH I68
J 0
(-3200 4375);
DISPLAY 0.872340 (-3200 4375);
PAINT AQUA (-3200 4375);
DISPLAY INVISIBLE (-3200 4375);
FORCEADD UNIVERSAL_GND..1
(-2100 3275);
FORCEPROP 3 LASTPIN (-2100 3325) SIG_NAME GND\g
J 0
(-2090 3335);
DISPLAY 0.659574 (-2090 3335);
PAINT MONO (-2090 3335);
DISPLAY INVISIBLE (-2090 3335);
FORCEPROP 2 LAST CDS_LIB pure_quanta_power
J 0
(-2100 3275);
DISPLAY INVISIBLE (-2100 3275);
FORCEPROP 1 LAST HDL_POWER GND
J 1
(-2075 3200);
DISPLAY 0.872340 (-2075 3200);
PAINT GREEN (-2075 3200);
DISPLAY INVISIBLE (-2075 3200);
FORCEPROP 1 LAST PATH I69
J 0
(-2025 3275);
DISPLAY 0.872340 (-2025 3275);
PAINT AQUA (-2025 3275);
DISPLAY INVISIBLE (-2025 3275);
FORCEADD VCC_CORE..1
R 5
(-7200 1700);
FORCEPROP 3 LASTPIN (-7250 1700) SIG_NAME P3V3_AUX\g
J 0
(-7240 1710);
DISPLAY 0.659574 (-7240 1710);
PAINT MONO (-7240 1710);
DISPLAY INVISIBLE (-7240 1710);
FORCEPROP 1 LAST HDL_POWER P3V3_AUX
J 1
(-7025 1700);
DISPLAY 0.489362 (-7025 1700);
PAINT GREEN (-7025 1700);
FORCEPROP 2 LAST CDS_LIB pure_quanta_power
R 3
J 0
(-7200 1700);
DISPLAY INVISIBLE (-7200 1700);
FORCEPROP 1 LAST PATH I7
R 3
J 0
(-7175 1650);
DISPLAY 0.872340 (-7175 1650);
PAINT AQUA (-7175 1650);
DISPLAY INVISIBLE (-7175 1650);
FORCEADD Q_RES..2
(-2100 4100);
FORCEPROP 1 LAST LOCATION R2346
J 0
(-2055 4225);
DISPLAY 0.978723 (-2055 4225);
FORCEPROP 0 LAST $SEC 1
J 0
(-2050 4275);
DISPLAY 0.680851 (-2050 4275);
PAINT MONO (-2050 4275);
DISPLAY INVISIBLE (-2050 4275);
FORCEPROP 0 LAST CDS_SEC 1
J 0
(-2050 4275);
DISPLAY 1.021277 (-2050 4275);
DISPLAY INVISIBLE (-2050 4275);
FORCEPROP 1 LASTPIN (-2100 4200) $PN 1
J 0
(-2095 4162);
DISPLAY 0.787234 (-2095 4162);
PAINT MONO (-2095 4162);
FORCEPROP 1 LASTPIN (-2100 4000) $PN 2
J 0
(-2095 4010);
DISPLAY 0.787234 (-2095 4010);
PAINT MONO (-2095 4010);
FORCEPROP 1 LAST TOLERANCE 1%
J 0
(-2055 4125);
DISPLAY 0.510638 (-2055 4125);
FORCEPROP 1 LAST VALUE 100K
J 0
(-2055 4175);
DISPLAY 0.510638 (-2055 4175);
FORCEPROP 1 LAST WATTAGE 1/16W
J 0
(-2060 4075);
DISPLAY 0.510638 (-2060 4075);
FORCEPROP 1 LAST MATERIAL CHIP
J 0
(-2060 4025);
DISPLAY 0.510638 (-2060 4025);
FORCEPROP 1 LAST PACK_TYPE 0402LF
J 0
(-2060 3925);
DISPLAY 0.510638 (-2060 3925);
FORCEPROP 2 LAST CDS_LIB pure_quanta
J 0
(-2100 4100);
DISPLAY INVISIBLE (-2100 4100);
FORCEPROP 1 LAST PATH I70
J 0
(-2050 4275);
DISPLAY 0.978723 (-2050 4275);
PAINT WHITE (-2050 4275);
DISPLAY INVISIBLE (-2050 4275);
FORCEPROP 1 LAST PART_NUMBER CS41002FB09
J 0
(-2060 3975);
DISPLAY 0.510638 (-2060 3975);
DISPLAY INVISIBLE (-2060 3975);
FORCEADD UNIVERSAL_POWER..1
(-2100 4350);
FORCEPROP 3 LASTPIN (-2100 4300) SIG_NAME P3V3_AUX\g
J 0
(-2090 4310);
DISPLAY 0.659574 (-2090 4310);
PAINT MONO (-2090 4310);
DISPLAY INVISIBLE (-2090 4310);
FORCEPROP 1 LAST HDL_POWER P3V3_AUX
J 1
(-2100 4400);
DISPLAY 0.872340 (-2100 4400);
PAINT GREEN (-2100 4400);
FORCEPROP 2 LAST CDS_LIB pure_quanta_power
J 0
(-2100 4350);
DISPLAY INVISIBLE (-2100 4350);
FORCEPROP 1 LAST PATH I71
J 0
(-2050 4375);
DISPLAY 0.872340 (-2050 4375);
PAINT AQUA (-2050 4375);
DISPLAY INVISIBLE (-2050 4375);
FORCEADD MOSFET_NCH_DUAL..2
(-2150 3575);
FORCEPROP 1 LAST LOCATION Q50
J 0
(-1999 3551);
DISPLAY 0.723404 (-1999 3551);
PAINT GREEN (-1999 3551);
FORCEPROP 0 LAST $SEC 2
J 0
(-1975 3700);
DISPLAY 0.680851 (-1975 3700);
PAINT MONO (-1975 3700);
DISPLAY INVISIBLE (-1975 3700);
FORCEPROP 0 LAST CDS_SEC 2
J 0
(-1975 3700);
DISPLAY 1.021277 (-1975 3700);
DISPLAY INVISIBLE (-1975 3700);
FORCEPROP 0 LASTPIN (-2100 3775) $PN 3
R 1
J 0
(-2110 3785);
DISPLAY 0.680851 (-2110 3785);
PAINT MONO (-2110 3785);
FORCEPROP 0 LASTPIN (-2350 3525) $PN 5
J 2
(-2360 3535);
DISPLAY 0.680851 (-2360 3535);
PAINT MONO (-2360 3535);
FORCEPROP 0 LASTPIN (-2100 3375) $PN 4
R 1
J 2
(-2110 3365);
DISPLAY 0.680851 (-2110 3365);
PAINT MONO (-2110 3365);
FORCEPROP 2 LAST VALUE PJT138K
J 0
(-1975 3600);
DISPLAY 0.680851 (-1975 3600);
FORCEPROP 2 LAST PART_TYPE SMLF
J 0
(-1975 3650);
DISPLAY 0.680851 (-1975 3650);
FORCEPROP 1 LAST MATERIAL IC
J 0
(-1999 3426);
DISPLAY 0.723404 (-1999 3426);
PAINT GREEN (-1999 3426);
FORCEPROP 2 LAST CDS_LIB pure_quanta
J 0
(-2150 3575);
DISPLAY INVISIBLE (-2150 3575);
FORCEPROP 1 LAST CDS_LMAN_SYM_OUTLINE -150,150,150,-150
J 0
(-2150 3575);
DISPLAY 0.468085 (-2150 3575);
PAINT GREEN (-2150 3575);
DISPLAY INVISIBLE (-2150 3575);
FORCEPROP 1 LAST NEEDS_NO_SIZE TRUE
J 0
(-2000 3466);
DISPLAY 0.468085 (-2000 3466);
PAINT GREEN (-2000 3466);
DISPLAY INVISIBLE (-2000 3466);
FORCEPROP 1 LAST PATH I73
J 0
(-2000 3425);
DISPLAY 0.723404 (-2000 3425);
PAINT GREEN (-2000 3425);
DISPLAY INVISIBLE (-2000 3425);
FORCEPROP 1 LAST PART_NUMBER BAM138K0003
J 0
(-1999 3481);
DISPLAY 0.723404 (-1999 3481);
PAINT GREEN (-1999 3481);
DISPLAY INVISIBLE (-1999 3481);
FORCEADD OFFPAGE..2
(-6725 1000);
FORCEPROP 2 LAST $XR0 128 
J 0
(-6536 1000);
DISPLAY 0.638298 (-6536 1000);
PAINT MONO (-6536 1000);
FORCEPROP 2 LAST CDS_LIB standard
J 0
(-6725 1000);
DISPLAY INVISIBLE (-6725 1000);
FORCEPROP 1 LAST OFFPAGE TRUE
J 0
(-6400 875);
DISPLAY 0.872340 (-6400 875);
PAINT GREEN (-6400 875);
DISPLAY INVISIBLE (-6400 875);
FORCEPROP 1 LAST COMMENT_BODY TRUE
J 0
(-6770 905);
DISPLAY 0.872340 (-6770 905);
PAINT GREEN (-6770 905);
DISPLAY INVISIBLE (-6770 905);
FORCEPROP 2 LAST PATH I74
J 0
(-6550 1075);
DISPLAY 0.680851 (-6550 1075);
DISPLAY INVISIBLE (-6550 1075);
FORCEADD Q_RES..1
(-7550 1000);
FORCEPROP 1 LAST LOCATION R6113
J 0
(-7450 1000);
DISPLAY 0.489362 (-7450 1000);
PAINT SKYBLUE (-7450 1000);
FORCEPROP 0 LAST $SEC 1
J 0
(-7450 1050);
DISPLAY 0.680851 (-7450 1050);
PAINT MONO (-7450 1050);
DISPLAY INVISIBLE (-7450 1050);
FORCEPROP 0 LAST CDS_SEC 1
J 0
(-7450 1050);
DISPLAY 0.680851 (-7450 1050);
DISPLAY INVISIBLE (-7450 1050);
FORCEPROP 1 LASTPIN (-7650 1000) $PN 1
J 0
(-7638 1012);
DISPLAY 0.489362 (-7638 1012);
PAINT MONO (-7638 1012);
FORCEPROP 1 LASTPIN (-7450 1000) $PN 2
J 0
(-7488 1012);
DISPLAY 0.489362 (-7488 1012);
PAINT MONO (-7488 1012);
FORCEPROP 1 LAST VALUE 33.2
J 2
(-7675 1000);
DISPLAY 0.489362 (-7675 1000);
PAINT SKYBLUE (-7675 1000);
FORCEPROP 2 LAST BOM_COST MEM
J 2
(-7525 1150);
DISPLAY 0.744681 (-7525 1150);
PAINT WHITE (-7525 1150);
DISPLAY INVISIBLE (-7525 1150);
FORCEPROP 1 LAST WATTAGE 1/16W
J 2
(-7625 925);
DISPLAY 0.489362 (-7625 925);
PAINT SKYBLUE (-7625 925);
DISPLAY INVISIBLE (-7625 925);
FORCEPROP 1 LAST MATERIAL CHIP
J 2
(-7375 975);
DISPLAY 0.489362 (-7375 975);
PAINT SKYBLUE (-7375 975);
DISPLAY INVISIBLE (-7375 975);
FORCEPROP 1 LAST PACK_TYPE 0402LF
J 2
(-7375 925);
DISPLAY 0.489362 (-7375 925);
PAINT SKYBLUE (-7375 925);
DISPLAY INVISIBLE (-7375 925);
FORCEPROP 1 LAST TOLERANCE 1%
J 0
(-7675 975);
DISPLAY 0.489362 (-7675 975);
PAINT SKYBLUE (-7675 975);
DISPLAY INVISIBLE (-7675 975);
FORCEPROP 2 LAST CDS_LIB pure_quanta
J 0
(-7550 1000);
DISPLAY INVISIBLE (-7550 1000);
FORCEPROP 1 LAST PATH I75
J 0
(-7600 1150);
DISPLAY 0.978723 (-7600 1150);
PAINT WHITE (-7600 1150);
DISPLAY INVISIBLE (-7600 1150);
FORCEPROP 1 LAST PART_NUMBER CS03322FB03
J 2
(-7450 1050);
DISPLAY 0.489362 (-7450 1050);
PAINT SKYBLUE (-7450 1050);
DISPLAY INVISIBLE (-7450 1050);
FORCEADD OFFPAGE..1
(-8375 1000);
FORCEPROP 2 LAST $XR1 83 
J 0
(-8716 1000);
DISPLAY 0.638298 (-8716 1000);
PAINT MONO (-8716 1000);
FORCEPROP 2 LAST $XR0 81 
J 0
(-8626 1000);
DISPLAY 0.638298 (-8626 1000);
PAINT MONO (-8626 1000);
FORCEPROP 2 LAST CDS_LIB standard
J 0
(-8375 1000);
DISPLAY INVISIBLE (-8375 1000);
FORCEPROP 1 LAST OFFPAGE TRUE
J 0
(-8045 870);
PAINT GREEN (-8045 870);
DISPLAY INVISIBLE (-8045 870);
FORCEPROP 1 LAST COMMENT_BODY TRUE
J 0
(-8245 900);
DISPLAY 1.106383 (-8245 900);
PAINT PEACH (-8245 900);
DISPLAY INVISIBLE (-8245 900);
FORCEPROP 2 LAST PATH I76
J 0
(-8325 1075);
DISPLAY 0.680851 (-8325 1075);
DISPLAY INVISIBLE (-8325 1075);
FORCEADD Q_RES..2
(-2950 1225);
FORCEPROP 1 LAST LOCATION R6090
J 0
(-2905 1350);
DISPLAY 0.978723 (-2905 1350);
FORCEPROP 0 LAST $SEC 1
J 0
(-2900 1400);
DISPLAY 0.680851 (-2900 1400);
PAINT MONO (-2900 1400);
DISPLAY INVISIBLE (-2900 1400);
FORCEPROP 0 LAST CDS_SEC 1
J 0
(-2900 1400);
DISPLAY 1.021277 (-2900 1400);
DISPLAY INVISIBLE (-2900 1400);
FORCEPROP 1 LASTPIN (-2950 1325) $PN 1
J 0
(-2945 1287);
DISPLAY 0.787234 (-2945 1287);
PAINT MONO (-2945 1287);
FORCEPROP 1 LASTPIN (-2950 1125) $PN 2
J 0
(-2945 1135);
DISPLAY 0.787234 (-2945 1135);
PAINT MONO (-2945 1135);
FORCEPROP 1 LAST MATERIAL CHIP
J 0
(-2910 1150);
DISPLAY 0.510638 (-2910 1150);
FORCEPROP 1 LAST PACK_TYPE 0402LF
J 0
(-2910 1100);
DISPLAY 0.510638 (-2910 1100);
FORCEPROP 1 LAST VALUE 4.7K
J 0
(-2905 1300);
DISPLAY 0.510638 (-2905 1300);
FORCEPROP 1 LAST TOLERANCE 5%
J 0
(-2905 1250);
DISPLAY 0.510638 (-2905 1250);
FORCEPROP 1 LAST WATTAGE 1/16W
J 0
(-2910 1200);
DISPLAY 0.510638 (-2910 1200);
FORCEPROP 2 LAST CDS_LIB pure_quanta
J 0
(-2950 1225);
DISPLAY INVISIBLE (-2950 1225);
FORCEPROP 1 LAST PATH I77
J 0
(-2900 1400);
DISPLAY 0.978723 (-2900 1400);
PAINT WHITE (-2900 1400);
DISPLAY INVISIBLE (-2900 1400);
FORCEPROP 1 LAST PART_NUMBER CS24702JB10
J 0
(-2910 1050);
DISPLAY 0.510638 (-2910 1050);
DISPLAY INVISIBLE (-2910 1050);
FORCEADD UNIVERSAL_GND..1
(-2950 950);
FORCEPROP 3 LASTPIN (-2950 1000) SIG_NAME GND\g
J 0
(-2940 1010);
DISPLAY 0.659574 (-2940 1010);
PAINT MONO (-2940 1010);
DISPLAY INVISIBLE (-2940 1010);
FORCEPROP 2 LAST CDS_LIB pure_quanta_power
J 0
(-2950 950);
DISPLAY INVISIBLE (-2950 950);
FORCEPROP 1 LAST HDL_POWER GND
J 1
(-2925 875);
DISPLAY 0.872340 (-2925 875);
PAINT GREEN (-2925 875);
DISPLAY INVISIBLE (-2925 875);
FORCEPROP 1 LAST PATH I78
J 0
(-2875 950);
DISPLAY 0.872340 (-2875 950);
PAINT AQUA (-2875 950);
DISPLAY INVISIBLE (-2875 950);
FORCEADD OFFPAGE..2
(-6250 1925);
FORCEPROP 2 LAST $XR0 145 
J 0
(-6061 1925);
DISPLAY 0.638298 (-6061 1925);
PAINT MONO (-6061 1925);
FORCEPROP 2 LAST CDS_LIB standard
J 0
(-6250 1925);
DISPLAY INVISIBLE (-6250 1925);
FORCEPROP 1 LAST OFFPAGE TRUE
J 0
(-5925 1800);
DISPLAY 0.872340 (-5925 1800);
PAINT GREEN (-5925 1800);
DISPLAY INVISIBLE (-5925 1800);
FORCEPROP 1 LAST COMMENT_BODY TRUE
J 0
(-6295 1830);
DISPLAY 0.872340 (-6295 1830);
PAINT GREEN (-6295 1830);
DISPLAY INVISIBLE (-6295 1830);
FORCEPROP 2 LAST PATH I8
J 0
(-6050 1975);
DISPLAY 0.680851 (-6050 1975);
DISPLAY INVISIBLE (-6050 1975);
FORCEADD OFFPAGE..2
(-6725 875);
FORCEPROP 2 LAST $XR0 150 
J 0
(-6536 875);
DISPLAY 0.638298 (-6536 875);
PAINT MONO (-6536 875);
FORCEPROP 2 LAST CDS_LIB standard
J 0
(-6725 875);
DISPLAY INVISIBLE (-6725 875);
FORCEPROP 1 LAST OFFPAGE TRUE
J 0
(-6400 750);
DISPLAY 0.872340 (-6400 750);
PAINT GREEN (-6400 750);
DISPLAY INVISIBLE (-6400 750);
FORCEPROP 1 LAST COMMENT_BODY TRUE
J 0
(-6770 780);
DISPLAY 0.872340 (-6770 780);
PAINT GREEN (-6770 780);
DISPLAY INVISIBLE (-6770 780);
FORCEPROP 2 LAST PATH I81
J 0
(-6550 950);
DISPLAY 0.680851 (-6550 950);
DISPLAY INVISIBLE (-6550 950);
FORCEADD Q_RES..1
(-7550 875);
FORCEPROP 1 LAST LOCATION R6092
J 0
(-7450 875);
DISPLAY 0.489362 (-7450 875);
PAINT SKYBLUE (-7450 875);
FORCEPROP 0 LAST $SEC 1
J 0
(-7450 925);
DISPLAY 0.680851 (-7450 925);
PAINT MONO (-7450 925);
DISPLAY INVISIBLE (-7450 925);
FORCEPROP 0 LAST CDS_SEC 1
J 0
(-7450 925);
DISPLAY 0.680851 (-7450 925);
DISPLAY INVISIBLE (-7450 925);
FORCEPROP 1 LASTPIN (-7650 875) $PN 1
J 0
(-7638 887);
DISPLAY 0.489362 (-7638 887);
PAINT MONO (-7638 887);
FORCEPROP 1 LASTPIN (-7450 875) $PN 2
J 0
(-7488 887);
DISPLAY 0.489362 (-7488 887);
PAINT MONO (-7488 887);
FORCEPROP 1 LAST VALUE 0
J 2
(-7675 875);
DISPLAY 0.489362 (-7675 875);
PAINT SKYBLUE (-7675 875);
FORCEPROP 2 LAST CDS_LIB pure_quanta
J 0
(-7550 875);
DISPLAY INVISIBLE (-7550 875);
FORCEPROP 2 LAST BOM_COST MEM
J 2
(-7525 1025);
DISPLAY 0.744681 (-7525 1025);
PAINT WHITE (-7525 1025);
DISPLAY INVISIBLE (-7525 1025);
FORCEPROP 1 LAST WATTAGE 1/16W
J 2
(-7625 800);
DISPLAY 0.489362 (-7625 800);
PAINT SKYBLUE (-7625 800);
DISPLAY INVISIBLE (-7625 800);
FORCEPROP 1 LAST MATERIAL CHIP
J 2
(-7375 850);
DISPLAY 0.489362 (-7375 850);
PAINT SKYBLUE (-7375 850);
DISPLAY INVISIBLE (-7375 850);
FORCEPROP 1 LAST TOLERANCE 5%
J 0
(-7675 850);
DISPLAY 0.489362 (-7675 850);
PAINT SKYBLUE (-7675 850);
DISPLAY INVISIBLE (-7675 850);
FORCEPROP 1 LAST PACK_TYPE 0402LF
J 2
(-7375 800);
DISPLAY 0.489362 (-7375 800);
PAINT SKYBLUE (-7375 800);
DISPLAY INVISIBLE (-7375 800);
FORCEPROP 1 LAST PATH I82
J 0
(-7600 1025);
DISPLAY 0.978723 (-7600 1025);
PAINT WHITE (-7600 1025);
DISPLAY INVISIBLE (-7600 1025);
FORCEPROP 1 LAST PART_NUMBER CS00002JB13
J 2
(-7450 925);
DISPLAY 0.489362 (-7450 925);
PAINT SKYBLUE (-7450 925);
DISPLAY INVISIBLE (-7450 925);
FORCEADD OFFPAGE..1
(-8375 875);
FORCEPROP 2 LAST $XR0 80 
J 0
(-8626 875);
DISPLAY 0.638298 (-8626 875);
PAINT MONO (-8626 875);
FORCEPROP 2 LAST CDS_LIB standard
J 0
(-8375 875);
DISPLAY INVISIBLE (-8375 875);
FORCEPROP 1 LAST OFFPAGE TRUE
J 0
(-8045 745);
PAINT GREEN (-8045 745);
DISPLAY INVISIBLE (-8045 745);
FORCEPROP 1 LAST COMMENT_BODY TRUE
J 0
(-8245 775);
DISPLAY 1.106383 (-8245 775);
PAINT PEACH (-8245 775);
DISPLAY INVISIBLE (-8245 775);
FORCEPROP 2 LAST PATH I83
J 0
(-8325 950);
DISPLAY 0.680851 (-8325 950);
DISPLAY INVISIBLE (-8325 950);
FORCEADD Q_RES..1
(-7550 775);
FORCEPROP 1 LAST LOCATION R6093
J 0
(-7450 775);
DISPLAY 0.489362 (-7450 775);
PAINT SKYBLUE (-7450 775);
FORCEPROP 0 LAST $SEC 1
J 0
(-7450 825);
DISPLAY 0.680851 (-7450 825);
PAINT MONO (-7450 825);
DISPLAY INVISIBLE (-7450 825);
FORCEPROP 0 LAST CDS_SEC 1
J 0
(-7450 825);
DISPLAY 0.680851 (-7450 825);
DISPLAY INVISIBLE (-7450 825);
FORCEPROP 1 LASTPIN (-7650 775) $PN 1
J 0
(-7638 787);
DISPLAY 0.489362 (-7638 787);
PAINT MONO (-7638 787);
FORCEPROP 1 LASTPIN (-7450 775) $PN 2
J 0
(-7488 787);
DISPLAY 0.489362 (-7488 787);
PAINT MONO (-7488 787);
FORCEPROP 1 LAST VALUE 0
J 2
(-7675 775);
DISPLAY 0.489362 (-7675 775);
PAINT SKYBLUE (-7675 775);
FORCEPROP 1 LAST PACK_TYPE 0402LF
J 2
(-7375 700);
DISPLAY 0.489362 (-7375 700);
PAINT SKYBLUE (-7375 700);
DISPLAY INVISIBLE (-7375 700);
FORCEPROP 1 LAST TOLERANCE 5%
J 0
(-7675 750);
DISPLAY 0.489362 (-7675 750);
PAINT SKYBLUE (-7675 750);
DISPLAY INVISIBLE (-7675 750);
FORCEPROP 1 LAST MATERIAL CHIP
J 2
(-7375 750);
DISPLAY 0.489362 (-7375 750);
PAINT SKYBLUE (-7375 750);
DISPLAY INVISIBLE (-7375 750);
FORCEPROP 1 LAST WATTAGE 1/16W
J 2
(-7625 700);
DISPLAY 0.489362 (-7625 700);
PAINT SKYBLUE (-7625 700);
DISPLAY INVISIBLE (-7625 700);
FORCEPROP 2 LAST BOM_COST MEM
J 2
(-7525 925);
DISPLAY 0.744681 (-7525 925);
PAINT WHITE (-7525 925);
DISPLAY INVISIBLE (-7525 925);
FORCEPROP 2 LAST CDS_LIB pure_quanta
J 0
(-7550 775);
DISPLAY INVISIBLE (-7550 775);
FORCEPROP 1 LAST PATH I84
J 0
(-7600 925);
DISPLAY 0.978723 (-7600 925);
PAINT WHITE (-7600 925);
DISPLAY INVISIBLE (-7600 925);
FORCEPROP 1 LAST PART_NUMBER CS00002JB13
J 2
(-7450 825);
DISPLAY 0.489362 (-7450 825);
PAINT SKYBLUE (-7450 825);
DISPLAY INVISIBLE (-7450 825);
FORCEADD OFFPAGE..2
(-6725 775);
FORCEPROP 2 LAST $XR0 255 
J 0
(-6536 775);
DISPLAY 0.638298 (-6536 775);
PAINT MONO (-6536 775);
FORCEPROP 2 LAST CDS_LIB standard
J 0
(-6725 775);
DISPLAY INVISIBLE (-6725 775);
FORCEPROP 1 LAST OFFPAGE TRUE
J 0
(-6400 650);
DISPLAY 0.872340 (-6400 650);
PAINT GREEN (-6400 650);
DISPLAY INVISIBLE (-6400 650);
FORCEPROP 1 LAST COMMENT_BODY TRUE
J 0
(-6770 680);
DISPLAY 0.872340 (-6770 680);
PAINT GREEN (-6770 680);
DISPLAY INVISIBLE (-6770 680);
FORCEPROP 2 LAST PATH I85
J 0
(-6550 850);
DISPLAY 0.680851 (-6550 850);
DISPLAY INVISIBLE (-6550 850);
FORCEADD Q_CAP..1
(-7150 550);
FORCEPROP 1 LAST LOCATION C1209
J 0
(-7100 650);
DISPLAY 0.638298 (-7100 650);
FORCEPROP 0 LAST $SEC 1
J 0
(-7100 700);
DISPLAY 0.680851 (-7100 700);
PAINT MONO (-7100 700);
DISPLAY INVISIBLE (-7100 700);
FORCEPROP 0 LAST CDS_SEC 1
J 0
(-7100 700);
DISPLAY 0.680851 (-7100 700);
DISPLAY INVISIBLE (-7100 700);
FORCEPROP 1 LASTPIN (-7150 650) $PN 1
J 0
(-7140 630);
DISPLAY 0.787234 (-7140 630);
PAINT MONO (-7140 630);
FORCEPROP 1 LASTPIN (-7150 450) $PN 2
J 0
(-7140 430);
DISPLAY 0.787234 (-7140 430);
PAINT MONO (-7140 430);
FORCEPROP 1 LAST PACK_TYPE 0402
J 0
(-7100 350);
DISPLAY 0.638298 (-7100 350);
FORCEPROP 1 LAST MATERIAL NPO
J 0
(-7100 450);
DISPLAY 0.638298 (-7100 450);
FORCEPROP 1 LAST TOLERANCE 5%
J 0
(-7100 500);
DISPLAY 0.638298 (-7100 500);
FORCEPROP 1 LAST VOLTAGE 50V
J 0
(-7100 550);
DISPLAY 0.638298 (-7100 550);
FORCEPROP 1 LAST VALUE 100PF
J 0
(-7100 600);
DISPLAY 0.638298 (-7100 600);
FORCEPROP 2 LAST CDS_LIB pure_quanta
J 0
(-7150 550);
DISPLAY INVISIBLE (-7150 550);
FORCEPROP 1 LAST PATH I88
J 0
(-7100 700);
DISPLAY 0.978723 (-7100 700);
PAINT WHITE (-7100 700);
DISPLAY INVISIBLE (-7100 700);
FORCEPROP 1 LAST PART_NUMBER CH11006JB00
J 0
(-7100 400);
DISPLAY 0.638298 (-7100 400);
DISPLAY INVISIBLE (-7100 400);
FORCEADD UNIVERSAL_GND..1
(-7150 275);
FORCEPROP 3 LASTPIN (-7150 325) SIG_NAME GND\g
J 0
(-7140 335);
DISPLAY 0.659574 (-7140 335);
PAINT MONO (-7140 335);
DISPLAY INVISIBLE (-7140 335);
FORCEPROP 2 LAST CDS_LIB pure_quanta_power
J 0
(-7150 275);
DISPLAY INVISIBLE (-7150 275);
FORCEPROP 1 LAST HDL_POWER GND
J 1
(-7125 200);
DISPLAY 0.872340 (-7125 200);
PAINT GREEN (-7125 200);
DISPLAY INVISIBLE (-7125 200);
FORCEPROP 1 LAST PATH I89
J 0
(-7075 275);
DISPLAY 0.872340 (-7075 275);
PAINT AQUA (-7075 275);
DISPLAY INVISIBLE (-7075 275);
FORCEADD OFFPAGE..2
(-6725 1150);
FORCEPROP 2 LAST $XR0 128 
J 0
(-6536 1150);
DISPLAY 0.638298 (-6536 1150);
PAINT MONO (-6536 1150);
FORCEPROP 2 LAST CDS_LIB standard
J 0
(-6725 1150);
DISPLAY INVISIBLE (-6725 1150);
FORCEPROP 1 LAST OFFPAGE TRUE
J 0
(-6400 1025);
DISPLAY 0.872340 (-6400 1025);
PAINT GREEN (-6400 1025);
DISPLAY INVISIBLE (-6400 1025);
FORCEPROP 1 LAST COMMENT_BODY TRUE
J 0
(-6770 1055);
DISPLAY 0.872340 (-6770 1055);
PAINT GREEN (-6770 1055);
DISPLAY INVISIBLE (-6770 1055);
FORCEPROP 2 LAST PATH I90
J 0
(-6525 1200);
DISPLAY 0.680851 (-6525 1200);
DISPLAY INVISIBLE (-6525 1200);
FORCEADD Q_RES..1
(-7550 1150);
FORCEPROP 1 LAST LOCATION R6112
J 0
(-7450 1150);
DISPLAY 0.489362 (-7450 1150);
PAINT SKYBLUE (-7450 1150);
FORCEPROP 0 LAST $SEC 1
J 0
(-7450 1200);
DISPLAY 0.680851 (-7450 1200);
PAINT MONO (-7450 1200);
DISPLAY INVISIBLE (-7450 1200);
FORCEPROP 0 LAST CDS_SEC 1
J 0
(-7450 1200);
DISPLAY 0.680851 (-7450 1200);
DISPLAY INVISIBLE (-7450 1200);
FORCEPROP 1 LASTPIN (-7650 1150) $PN 1
J 0
(-7638 1162);
DISPLAY 0.489362 (-7638 1162);
PAINT MONO (-7638 1162);
FORCEPROP 1 LASTPIN (-7450 1150) $PN 2
J 0
(-7488 1162);
DISPLAY 0.489362 (-7488 1162);
PAINT MONO (-7488 1162);
FORCEPROP 1 LAST VALUE 33.2
J 2
(-7675 1150);
DISPLAY 0.489362 (-7675 1150);
PAINT SKYBLUE (-7675 1150);
FORCEPROP 2 LAST CDS_LIB pure_quanta
J 0
(-7550 1150);
DISPLAY INVISIBLE (-7550 1150);
FORCEPROP 2 LAST BOM_COST MEM
J 2
(-7525 1300);
DISPLAY 0.744681 (-7525 1300);
PAINT WHITE (-7525 1300);
DISPLAY INVISIBLE (-7525 1300);
FORCEPROP 1 LAST WATTAGE 1/16W
J 2
(-7625 1075);
DISPLAY 0.489362 (-7625 1075);
PAINT SKYBLUE (-7625 1075);
DISPLAY INVISIBLE (-7625 1075);
FORCEPROP 1 LAST MATERIAL CHIP
J 2
(-7375 1125);
DISPLAY 0.489362 (-7375 1125);
PAINT SKYBLUE (-7375 1125);
DISPLAY INVISIBLE (-7375 1125);
FORCEPROP 1 LAST PACK_TYPE 0402LF
J 2
(-7375 1075);
DISPLAY 0.489362 (-7375 1075);
PAINT SKYBLUE (-7375 1075);
DISPLAY INVISIBLE (-7375 1075);
FORCEPROP 1 LAST TOLERANCE 1%
J 0
(-7675 1125);
DISPLAY 0.489362 (-7675 1125);
PAINT SKYBLUE (-7675 1125);
DISPLAY INVISIBLE (-7675 1125);
FORCEPROP 1 LAST PATH I91
J 0
(-7600 1300);
DISPLAY 0.978723 (-7600 1300);
PAINT WHITE (-7600 1300);
DISPLAY INVISIBLE (-7600 1300);
FORCEPROP 1 LAST PART_NUMBER CS03322FB03
J 2
(-7450 1200);
DISPLAY 0.489362 (-7450 1200);
PAINT SKYBLUE (-7450 1200);
DISPLAY INVISIBLE (-7450 1200);
FORCEADD OFFPAGE..1
(-8375 1150);
FORCEPROP 2 LAST $XR1 83 
J 0
(-8716 1150);
DISPLAY 0.638298 (-8716 1150);
PAINT MONO (-8716 1150);
FORCEPROP 2 LAST $XR0 81 
J 0
(-8626 1150);
DISPLAY 0.638298 (-8626 1150);
PAINT MONO (-8626 1150);
FORCEPROP 2 LAST CDS_LIB standard
J 0
(-8375 1150);
DISPLAY INVISIBLE (-8375 1150);
FORCEPROP 1 LAST OFFPAGE TRUE
J 0
(-8045 1020);
PAINT GREEN (-8045 1020);
DISPLAY INVISIBLE (-8045 1020);
FORCEPROP 1 LAST COMMENT_BODY TRUE
J 0
(-8245 1050);
DISPLAY 1.106383 (-8245 1050);
PAINT PEACH (-8245 1050);
DISPLAY INVISIBLE (-8245 1050);
FORCEPROP 2 LAST PATH I92
J 0
(-8625 1200);
DISPLAY 0.680851 (-8625 1200);
DISPLAY INVISIBLE (-8625 1200);
FORCEADD OFFPAGE..2
(-6725 2100);
FORCEPROP 2 LAST $XR0 128 
J 0
(-6536 2100);
DISPLAY 0.638298 (-6536 2100);
PAINT MONO (-6536 2100);
FORCEPROP 2 LAST CDS_LIB standard
J 0
(-6725 2100);
DISPLAY INVISIBLE (-6725 2100);
FORCEPROP 1 LAST OFFPAGE TRUE
J 0
(-6400 1975);
DISPLAY 0.872340 (-6400 1975);
PAINT GREEN (-6400 1975);
DISPLAY INVISIBLE (-6400 1975);
FORCEPROP 1 LAST COMMENT_BODY TRUE
J 0
(-6770 2005);
DISPLAY 0.872340 (-6770 2005);
PAINT GREEN (-6770 2005);
DISPLAY INVISIBLE (-6770 2005);
FORCEPROP 2 LAST PATH I93
J 0
(-6550 2175);
DISPLAY 0.680851 (-6550 2175);
DISPLAY INVISIBLE (-6550 2175);
FORCEADD Q_RES..1
(-7550 2100);
FORCEPROP 1 LAST LOCATION R2
J 0
(-7450 2100);
DISPLAY 0.489362 (-7450 2100);
PAINT SKYBLUE (-7450 2100);
FORCEPROP 0 LAST $SEC 1
J 0
(-7450 2125);
DISPLAY 0.680851 (-7450 2125);
PAINT MONO (-7450 2125);
DISPLAY INVISIBLE (-7450 2125);
FORCEPROP 0 LAST CDS_SEC 1
J 0
(-7450 2125);
DISPLAY 0.680851 (-7450 2125);
DISPLAY INVISIBLE (-7450 2125);
FORCEPROP 1 LASTPIN (-7650 2100) $PN 1
J 0
(-7638 2112);
DISPLAY 0.787234 (-7638 2112);
PAINT MONO (-7638 2112);
FORCEPROP 1 LASTPIN (-7450 2100) $PN 2
J 0
(-7488 2112);
DISPLAY 0.787234 (-7488 2112);
PAINT MONO (-7488 2112);
FORCEPROP 1 LAST VALUE 33.2
J 2
(-7675 2100);
DISPLAY 0.489362 (-7675 2100);
PAINT SKYBLUE (-7675 2100);
FORCEPROP 2 LAST CDS_LIB pure_quanta
J 0
(-7550 2100);
DISPLAY INVISIBLE (-7550 2100);
FORCEPROP 1 LAST TOLERANCE 1%
J 0
(-7675 2075);
DISPLAY 0.489362 (-7675 2075);
PAINT SKYBLUE (-7675 2075);
DISPLAY INVISIBLE (-7675 2075);
FORCEPROP 1 LAST PACK_TYPE 0402LF
J 2
(-7375 2025);
DISPLAY 0.489362 (-7375 2025);
PAINT SKYBLUE (-7375 2025);
DISPLAY INVISIBLE (-7375 2025);
FORCEPROP 1 LAST MATERIAL CHIP
J 2
(-7375 2075);
DISPLAY 0.489362 (-7375 2075);
PAINT SKYBLUE (-7375 2075);
DISPLAY INVISIBLE (-7375 2075);
FORCEPROP 1 LAST WATTAGE 1/16W
J 2
(-7625 2025);
DISPLAY 0.489362 (-7625 2025);
PAINT SKYBLUE (-7625 2025);
DISPLAY INVISIBLE (-7625 2025);
FORCEPROP 2 LAST BOM_COST MEM
J 2
(-7525 2250);
DISPLAY 0.744681 (-7525 2250);
PAINT WHITE (-7525 2250);
DISPLAY INVISIBLE (-7525 2250);
FORCEPROP 1 LAST PATH I94
J 0
(-7600 2250);
DISPLAY 0.978723 (-7600 2250);
PAINT WHITE (-7600 2250);
DISPLAY INVISIBLE (-7600 2250);
FORCEPROP 1 LAST PART_NUMBER CS03322FB03
J 2
(-7450 2150);
DISPLAY 0.489362 (-7450 2150);
PAINT SKYBLUE (-7450 2150);
DISPLAY INVISIBLE (-7450 2150);
FORCEADD OFFPAGE..1
(-8375 2100);
FORCEPROP 2 LAST $XR1 83 
J 0
(-8716 2100);
DISPLAY 0.638298 (-8716 2100);
PAINT MONO (-8716 2100);
FORCEPROP 2 LAST $XR0 81 
J 0
(-8626 2100);
DISPLAY 0.638298 (-8626 2100);
PAINT MONO (-8626 2100);
FORCEPROP 2 LAST CDS_LIB standard
J 0
(-8375 2100);
DISPLAY INVISIBLE (-8375 2100);
FORCEPROP 1 LAST OFFPAGE TRUE
J 0
(-8045 1970);
PAINT GREEN (-8045 1970);
DISPLAY INVISIBLE (-8045 1970);
FORCEPROP 1 LAST COMMENT_BODY TRUE
J 0
(-8245 2000);
DISPLAY 1.106383 (-8245 2000);
PAINT PEACH (-8245 2000);
DISPLAY INVISIBLE (-8245 2000);
FORCEPROP 2 LAST PATH I95
J 0
(-8325 2175);
DISPLAY 0.680851 (-8325 2175);
DISPLAY INVISIBLE (-8325 2175);
FORCEADD Q_LED..1
(-2550 6050);
FORCEPROP 1 LAST LOCATION D7
J 2
(-2625 6125);
DISPLAY 0.489362 (-2625 6125);
PAINT SKYBLUE (-2625 6125);
FORCEPROP 0 LAST $SEC 1
J 0
(-2450 6225);
DISPLAY 0.680851 (-2450 6225);
PAINT MONO (-2450 6225);
DISPLAY INVISIBLE (-2450 6225);
FORCEPROP 0 LAST CDS_SEC 1
J 0
(-2450 6225);
DISPLAY 0.680851 (-2450 6225);
DISPLAY INVISIBLE (-2450 6225);
FORCEPROP 0 LASTPIN (-2700 6050) $PN A
J 2
(-2710 6060);
DISPLAY 0.680851 (-2710 6060);
PAINT MONO (-2710 6060);
FORCEPROP 0 LASTPIN (-2400 6050) $PN C
J 0
(-2390 6060);
DISPLAY 0.680851 (-2390 6060);
PAINT MONO (-2390 6060);
FORCEPROP 2 LAST COLOR LED_YELLOW
J 2
(-2300 6000);
DISPLAY 0.489362 (-2300 6000);
FORCEPROP 2 LAST MANUF_PN LTST-C190KSKT-P
J 2
(-2275 5950);
DISPLAY 0.680851 (-2275 5950);
FORCEPROP 2 LAST PACK_TYPE SMLF
J 2
(-2625 6000);
DISPLAY 0.489362 (-2625 6000);
PAINT SKYBLUE (-2625 6000);
FORCEPROP 1 LAST MATERIAL IC
J 2
(-2450 6130);
DISPLAY 0.489362 (-2450 6130);
PAINT SKYBLUE (-2450 6130);
FORCEPROP 2 LAST CDS_LIB pure_quanta
J 2
(-2550 6050);
DISPLAY INVISIBLE (-2550 6050);
FORCEPROP 1 LAST NEEDS_NO_SIZE TRUE
J 0
(-2550 6050);
DISPLAY 0.468085 (-2550 6050);
PAINT GREEN (-2550 6050);
DISPLAY INVISIBLE (-2550 6050);
FORCEPROP 1 LAST PATH I96
J 0
(-2425 6130);
DISPLAY 0.723404 (-2425 6130);
PAINT GREEN (-2425 6130);
DISPLAY INVISIBLE (-2425 6130);
FORCEPROP 1 LAST PART_NUMBER BEYL0159Z00
J 2
(-2450 6185);
DISPLAY 0.489362 (-2450 6185);
PAINT SKYBLUE (-2450 6185);
DISPLAY INVISIBLE (-2450 6185);
FORCEADD Q_LED..1
(-2525 5700);
FORCEPROP 1 LAST LOCATION D8
J 2
(-2600 5750);
DISPLAY 0.489362 (-2600 5750);
PAINT SKYBLUE (-2600 5750);
FORCEPROP 0 LAST $SEC 1
J 0
(-2425 5850);
DISPLAY 0.680851 (-2425 5850);
PAINT MONO (-2425 5850);
DISPLAY INVISIBLE (-2425 5850);
FORCEPROP 0 LAST CDS_SEC 1
J 0
(-2425 5850);
DISPLAY 0.680851 (-2425 5850);
DISPLAY INVISIBLE (-2425 5850);
FORCEPROP 0 LASTPIN (-2675 5700) $PN A
J 2
(-2685 5710);
DISPLAY 0.680851 (-2685 5710);
PAINT MONO (-2685 5710);
FORCEPROP 0 LASTPIN (-2375 5700) $PN C
J 0
(-2365 5710);
DISPLAY 0.680851 (-2365 5710);
PAINT MONO (-2365 5710);
FORCEPROP 2 LAST COLOR LED_YELLOW
J 2
(-2250 5650);
DISPLAY 0.489362 (-2250 5650);
FORCEPROP 1 LAST MATERIAL IC
J 2
(-2425 5780);
DISPLAY 0.489362 (-2425 5780);
PAINT SKYBLUE (-2425 5780);
FORCEPROP 2 LAST MANUF_PN LTST-C190KSKT-P
J 2
(-2325 5600);
DISPLAY 0.553191 (-2325 5600);
FORCEPROP 2 LAST PACK_TYPE SMLF
J 2
(-2625 5650);
DISPLAY 0.489362 (-2625 5650);
PAINT SKYBLUE (-2625 5650);
FORCEPROP 2 LAST CDS_LIB pure_quanta
J 0
(-2525 5700);
DISPLAY INVISIBLE (-2525 5700);
FORCEPROP 1 LAST NEEDS_NO_SIZE TRUE
J 0
(-2525 5700);
DISPLAY 0.468085 (-2525 5700);
PAINT GREEN (-2525 5700);
DISPLAY INVISIBLE (-2525 5700);
FORCEPROP 1 LAST PATH I97
J 0
(-2400 5780);
DISPLAY 0.723404 (-2400 5780);
PAINT GREEN (-2400 5780);
DISPLAY INVISIBLE (-2400 5780);
FORCEPROP 1 LAST PART_NUMBER BEYL0159Z00
J 2
(-2425 5825);
DISPLAY 0.489362 (-2425 5825);
PAINT SKYBLUE (-2425 5825);
DISPLAY INVISIBLE (-2425 5825);
FORCEADD DNS..2
(-4225 3875);
PAINT RED (-4225 3875);
FORCEPROP 2 LAST CDS_LIB mstr_misc
J 0
(-4225 3875);
DISPLAY INVISIBLE (-4225 3875);
FORCEPROP 1 LAST COMMENT_BODY TRUE
R 1
J 0
(-4150 3650);
DISPLAY 0.872340 (-4150 3650);
PAINT GREEN (-4150 3650);
DISPLAY INVISIBLE (-4150 3650);
FORCEADD QUANTA_TITLE_BLOCK_C..1
(0 0);
FORCEPROP 0 LAST CDS_CON_LAST_MODIFIED Thu Sep 14 16:12:16 2023
J 0
(-1885 15);
DISPLAY INVISIBLE (-1885 15);
FORCEPROP 1 LAST CUSTOM_TXT_CDS <CON_LAST_MODIFIED>
J 0
(-1885 15);
DISPLAY 0.978723 (-1885 15);
FORCEPROP 2 LAST CUSTOM_TXT_CDS <XR_PAGE_TITLE>
J 0
(-7890 5250);
DISPLAY 0.638298 (-7890 5250);
PAINT PINK (-7890 5250);
DISPLAY INVISIBLE (-7890 5250);
FORCEPROP 1 LAST CUSTOM_TXT_CDS <NAME_2>
J 0
(-3175 50);
FORCEPROP 1 LAST CUSTOM_TXT_CDS <NAME_1>
J 0
(-3175 175);
FORCEPROP 1 LAST CUSTOM_TXT_CDS <Q_NUMBER>
J 0
(-1403 103);
DISPLAY 1.212766 (-1403 103);
FORCEPROP 1 LAST CUSTOM_TXT_CDS <Q_PROJ>
J 0
(-2382 102);
DISPLAY 1.212766 (-2382 102);
FORCEPROP 1 LAST CUSTOM_TXT_CDS <Q_REV>
J 0
(-184 103);
DISPLAY 1.212766 (-184 103);
FORCEPROP 1 LAST CUSTOM_TXT_CDS <CON_PAGE_NUM> OF <CON_TOTAL_PAGES>
J 0
(-446 18);
DISPLAY 0.978723 (-446 18);
FORCEPROP 1 LAST Q_TITLE FPGA 6/6
J 0
(-9275 75);
DISPLAY 2.446809 (-9275 75);
PAINT GREEN (-9275 75);
FORCEPROP 2 LAST CDS_LIB pure_quanta
J 0
(0 0);
DISPLAY INVISIBLE (0 0);
FORCEPROP 1 LAST CDS_LMAN_SYM_OUTLINE -9475,6775,100,-125
J 0
(0 0);
DISPLAY 0.468085 (0 0);
PAINT GREEN (0 0);
DISPLAY INVISIBLE (0 0);
FORCEPROP 2 LAST PAGE_BORDER TRUE
J 0
(-7890 5250);
DISPLAY 0.638298 (-7890 5250);
PAINT PINK (-7890 5250);
DISPLAY INVISIBLE (-7890 5250);
FORCEPROP 2 LAST CDS_XR_PAGE_TITLE CR-85 : @T6G_MB_LIB.T6G(SCH_1):PAGE85
J 0
(-7890 5250);
DISPLAY 0.638298 (-7890 5250);
PAINT PINK (-7890 5250);
DISPLAY INVISIBLE (-7890 5250);
FORCEPROP 1 LAST Q_DEPT BU9
J 1
(-3763 49);
DISPLAY 1.957447 (-3763 49);
PAINT GREEN (-3763 49);
DISPLAY INVISIBLE (-3763 49);
FORCEPROP 1 LAST COMMENT_BODY TRUE
J 0
(12 -13);
DISPLAY 0.978723 (12 -13);
PAINT GREEN (12 -13);
DISPLAY INVISIBLE (12 -13);
FORCEADD DNS..2
(-8625 3625);
PAINT RED (-8625 3625);
FORCEPROP 2 LAST CDS_LIB mstr_misc
J 0
(-8625 3625);
DISPLAY INVISIBLE (-8625 3625);
FORCEPROP 1 LAST COMMENT_BODY TRUE
J 0
(-8625 3625);
DISPLAY INVISIBLE (-8625 3625);
FORCEADD DNS..2
(-7050 5075);
PAINT RED (-7050 5075);
FORCEPROP 2 LAST CDS_LIB mstr_misc
J 0
(-7050 5075);
DISPLAY INVISIBLE (-7050 5075);
FORCEPROP 1 LAST COMMENT_BODY TRUE
J 0
(-7050 5075);
DISPLAY INVISIBLE (-7050 5075);
WIRE 16 -1 (-925 3525)(-925 3350);
WIRE 16 -1 (-8625 3550)(-8625 3425);
WIRE 16 -1 (-7475 3700)(-7475 3575);
WIRE 16 -1 (-6325 4000)(-6325 3875);
WIRE 16 -1 (-5550 4050)(-5550 4000);
WIRE 16 -1 (-7475 4675)(-7475 4600);
WIRE 16 -1 (-6325 4800)(-6325 4725);
WIRE 16 -1 (-1675 1575)(-1750 1575);
WIRE 16 -1 (-1750 1575)(-1750 1450);
WIRE 16 -1 (-1975 5300)(-2050 5300);
WIRE 16 -1 (-2050 5300)(-2050 5225);
WIRE 16 -1 (-1375 5300)(-1275 5300);
WIRE 16 -1 (-1275 5300)(-1275 5225);
WIRE 16 -1 (-4225 4000)(-4225 4100);
WIRE 16 -1 (-3250 3375)(-3250 3325);
WIRE 16 -1 (-3250 4300)(-3250 4200);
WIRE 16 -1 (-2100 3325)(-2100 3375);
WIRE 16 -1 (-7250 1700)(-7525 1700);
WIRE 16 -1 (-2100 4300)(-2100 4200);
WIRE 16 -1 (-2950 1125)(-2950 1000);
WIRE 16 -1 (-7150 450)(-7150 325);
WIRE 16 -1 (-1725 1875)(-1725 2250);
WIRE 16 -1 (-1725 1875)(-1675 1875);
WIRE 16 -1 (-1850 2250)(-1725 2250);
WIRE 16 -1 (-1725 2250)(-1725 2325);
WIRE 16 -1 (-1850 2175)(-1850 2250);
WIRE 16 -1 (-7650 2100)(-8325 2100);
FORCEPROP 2 LAST SIG_NAME RST_PERST_CPU1_SWB_1_N
J 0
(-8310 2110);
DISPLAY 0.446809 (-8310 2110);
PAINT WHITE (-8310 2110);
WIRE 16 -1 (-7650 1150)(-8325 1150);
FORCEPROP 2 LAST SIG_NAME RST_PERST_CPU0_SWB_N
J 0
(-8260 1160);
DISPLAY 0.446809 (-8260 1160);
PAINT WHITE (-8260 1160);
WIRE 16 -1 (-8325 1300)(-7650 1300);
FORCEPROP 2 LAST SIG_NAME PWRGD_P3V3_AUX
J 0
(-8260 1310);
DISPLAY 0.446809 (-8260 1310);
PAINT WHITE (-8260 1310);
WIRE 16 -1 (-8325 1425)(-7650 1425);
FORCEPROP 2 LAST SIG_NAME LED_HDD_ACTIVITY_B_N
J 0
(-8260 1435);
DISPLAY 0.446809 (-8260 1435);
PAINT WHITE (-8260 1435);
WIRE 16 -1 (-8325 1550)(-7650 1550);
FORCEPROP 2 LAST SIG_NAME FM_THERMAL_ALERT_N
J 0
(-8260 1560);
DISPLAY 0.446809 (-8260 1560);
PAINT WHITE (-8260 1560);
WIRE 16 -1 (-7650 1000)(-8325 1000);
FORCEPROP 2 LAST SIG_NAME RST_PERST_CPU1_SWB_N
J 0
(-8260 1010);
DISPLAY 0.446809 (-8260 1010);
PAINT WHITE (-8260 1010);
WIRE 16 -1 (-7450 1150)(-6775 1150);
FORCEPROP 2 LAST SIG_NAME RST_PERST_CPU0_SWB_R_N
J 0
(-7300 1160);
DISPLAY 0.446809 (-7300 1160);
PAINT WHITE (-7300 1160);
WIRE 16 -1 (-6300 1925)(-7525 1925);
FORCEPROP 0 LAST SIG_NAME FM_SMB_RST_E1S_0_R_N
J 0
(-7085 1935);
DISPLAY 0.489362 (-7085 1935);
WIRE 16 -1 (-7450 2100)(-6775 2100);
FORCEPROP 2 LAST SIG_NAME RST_PERST_CPU1_SWB_1_R_N
J 0
(-7285 2110);
DISPLAY 0.446809 (-7285 2110);
PAINT WHITE (-7285 2110);
WIRE 16 -1 (-6775 875)(-7450 875);
FORCEPROP 2 LAST SIG_NAME SCM_SYS_PWROK_R1
J 0
(-7300 885);
DISPLAY 0.446809 (-7300 885);
PAINT WHITE (-7300 885);
WIRE 16 -1 (-7450 1000)(-6775 1000);
FORCEPROP 2 LAST SIG_NAME RST_PERST_CPU1_SWB_R_N
J 0
(-7300 1010);
DISPLAY 0.446809 (-7300 1010);
PAINT WHITE (-7300 1010);
WIRE 16 -1 (-7450 1300)(-6775 1300);
FORCEPROP 2 LAST SIG_NAME PWRGD_P3V3_AUX_PDB
J 0
(-7300 1310);
DISPLAY 0.446809 (-7300 1310);
PAINT WHITE (-7300 1310);
WIRE 16 -1 (-7450 775)(-7150 775);
FORCEPROP 2 LAST SIG_NAME SCM_SYS_PWROK_R2
J 0
(-7300 785);
DISPLAY 0.446809 (-7300 785);
PAINT WHITE (-7300 785);
WIRE 16 -1 (-7150 775)(-6775 775);
WIRE 16 -1 (-7150 775)(-7150 650);
WIRE 16 -1 (-7650 875)(-7825 875);
WIRE 16 -1 (-7825 875)(-7825 775);
WIRE 16 -1 (-7825 875)(-8325 875);
FORCEPROP 2 LAST SIG_NAME SCM_SYS_PWROK_R
J 0
(-8260 885);
DISPLAY 0.446809 (-8260 885);
PAINT WHITE (-8260 885);
WIRE 16 -1 (-7825 775)(-7650 775);
WIRE 16 -1 (-3450 1625)(-2675 1625);
FORCEPROP 2 LAST SIG_NAME JTAG_SCM_PLD_TMS
J 0
(-3410 1650);
DISPLAY 0.489362 (-3410 1650);
WIRE 16 -1 (-2475 1625)(-1675 1625);
FORCEPROP 2 LAST SIG_NAME JTAG_PLD_TMS
J 0
(-2185 1635);
DISPLAY 0.489362 (-2185 1635);
FORCEPROP 2 LASTPROP $XRERR UNIQUE?
J 0
(-2425 1635);
DISPLAY 0.638298 (-2425 1635);
PAINT MONO (-2425 1635);
DISPLAY INVISIBLE (-2425 1635);
WIRE 16 -1 (-3425 1825)(-2675 1825);
FORCEPROP 2 LAST SIG_NAME JTAG_SCM_PLD_TDI
J 0
(-3425 1835);
DISPLAY 0.489362 (-3425 1835);
WIRE 16 -1 (-2475 1825)(-1675 1825);
FORCEPROP 2 LAST SIG_NAME JTAG_PLD_TDI
J 0
(-2185 1835);
DISPLAY 0.489362 (-2185 1835);
FORCEPROP 2 LASTPROP $XRERR UNIQUE?
J 0
(-2425 1835);
DISPLAY 0.638298 (-2425 1835);
PAINT MONO (-2425 1835);
DISPLAY INVISIBLE (-2425 1835);
WIRE 16 -1 (-2475 1775)(-1675 1775);
FORCEPROP 2 LAST SIG_NAME JTAG_PLD_TDO
J 0
(-2185 1785);
DISPLAY 0.489362 (-2185 1785);
FORCEPROP 2 LASTPROP $XRERR UNIQUE?
J 0
(-2425 1785);
DISPLAY 0.638298 (-2425 1785);
PAINT MONO (-2425 1785);
DISPLAY INVISIBLE (-2425 1785);
WIRE 16 -1 (-3450 1525)(-2950 1525);
FORCEPROP 2 LAST SIG_NAME JTAG_SCM_PLD_TCK
J 0
(-3410 1550);
DISPLAY 0.489362 (-3410 1550);
WIRE 16 -1 (-2950 1525)(-2675 1525);
WIRE 16 -1 (-2950 1525)(-2950 1325);
WIRE 16 -1 (-2475 1525)(-1675 1525);
FORCEPROP 2 LAST SIG_NAME JTAG_PLD_TCK
J 0
(-2185 1535);
DISPLAY 0.489362 (-2185 1535);
FORCEPROP 2 LASTPROP $XRERR UNIQUE?
J 0
(-2425 1535);
DISPLAY 0.638298 (-2425 1535);
PAINT MONO (-2425 1535);
DISPLAY INVISIBLE (-2425 1535);
WIRE 16 -1 (-8325 1925)(-7850 1925);
WIRE 16 -1 (-7850 1925)(-7725 1925);
WIRE 16 -1 (-7850 1700)(-7850 1925);
WIRE 16 -1 (-7850 1700)(-7725 1700);
WIRE 16 -1 (-8650 6175)(-7825 6175);
FORCEPROP 2 LAST SIG_NAME PWRGD_CPU1_PWROK
J 0
(-8560 6185);
DISPLAY 0.489362 (-8560 6185);
WIRE 16 -1 (-8650 6375)(-7825 6375);
FORCEPROP 2 LAST SIG_NAME PWRGD_CPU0_PWROK
J 0
(-8560 6385);
DISPLAY 0.489362 (-8560 6385);
WIRE 16 -1 (-6525 6200)(-5750 6200);
FORCEPROP 2 LAST SIG_NAME RST_CPU1_RESETL_N
J 0
(-6300 6210);
DISPLAY 0.489362 (-6300 6210);
WIRE 16 -1 (-6525 6400)(-5750 6400);
FORCEPROP 2 LAST SIG_NAME RST_CPU0_RESETL_N
J 0
(-6300 6410);
DISPLAY 0.489362 (-6300 6410);
WIRE 16 -1 (-1325 6050)(-1325 5400);
WIRE 16 -1 (-2400 6050)(-1325 6050);
FORCEPROP 2 LAST SIG_NAME BMC_FPGA_LED2_N
J 0
(-2310 6060);
DISPLAY 0.489362 (-2310 6060);
FORCEPROP 2 LASTPROP $XRERR UNIQUE?
J 0
(-2550 6060);
DISPLAY 0.638298 (-2550 6060);
PAINT MONO (-2550 6060);
DISPLAY INVISIBLE (-2550 6060);
WIRE 16 -1 (-1325 5400)(-1375 5400);
WIRE 16 -1 (-2225 5700)(-2375 5700);
FORCEPROP 2 LAST SIG_NAME BMC_FPGA_LED1_N
J 0
(-2285 5710);
DISPLAY 0.489362 (-2285 5710);
FORCEPROP 2 LASTPROP $XRERR UNIQUE?
J 0
(-2525 5710);
DISPLAY 0.638298 (-2525 5710);
PAINT MONO (-2525 5710);
DISPLAY INVISIBLE (-2525 5710);
WIRE 16 -1 (-2225 5700)(-2225 5400);
WIRE 16 -1 (-2225 5400)(-1975 5400);
WIRE 16 -1 (-3800 6050)(-3925 6050);
WIRE 16 -1 (-3925 6250)(-3925 6050);
WIRE 16 -1 (-3925 6050)(-3925 5700);
WIRE 16 -1 (-3800 5700)(-3925 5700);
WIRE 16 -1 (-700 5350)(-1375 5350);
FORCEPROP 2 LAST SIG_NAME BMC_FPGA_LED2
J 0
(-1210 5360);
DISPLAY 0.489362 (-1210 5360);
WIRE 16 -1 (-2700 6050)(-3600 6050);
FORCEPROP 2 LAST SIG_NAME BMC_FPGA_LED2_R_N
J 0
(-3535 6060);
DISPLAY 0.489362 (-3535 6060);
FORCEPROP 2 LASTPROP $XRERR UNIQUE?
J 0
(-3775 6060);
DISPLAY 0.638298 (-3775 6060);
PAINT MONO (-3775 6060);
DISPLAY INVISIBLE (-3775 6060);
WIRE 16 -1 (-1975 5350)(-2825 5350);
FORCEPROP 2 LAST SIG_NAME BMC_FPGA_LED1
J 0
(-2660 5360);
DISPLAY 0.489362 (-2660 5360);
WIRE 16 -1 (-2675 5700)(-3600 5700);
FORCEPROP 2 LAST SIG_NAME BMC_FPGA_LED1_R_N
J 0
(-3535 5710);
DISPLAY 0.489362 (-3535 5710);
FORCEPROP 2 LASTPROP $XRERR UNIQUE?
J 0
(-3775 5710);
DISPLAY 0.638298 (-3775 5710);
PAINT MONO (-3775 5710);
DISPLAY INVISIBLE (-3775 5710);
WIRE 16 -1 (-2450 3850)(-2450 3525);
WIRE 16 -1 (-2450 3850)(-3250 3850);
FORCEPROP 2 LAST SIG_NAME PWRGD_P5V_AUX_R1
J 0
(-3160 3860);
DISPLAY 0.553191 (-3160 3860);
PAINT WHITE (-3160 3860);
FORCEPROP 2 LASTPROP $XRERR UNIQUE?
J 0
(-3400 3860);
DISPLAY 0.638298 (-3400 3860);
PAINT MONO (-3400 3860);
DISPLAY INVISIBLE (-3400 3860);
WIRE 16 -1 (-2450 3525)(-2350 3525);
WIRE 16 -1 (-3250 4000)(-3250 3850);
WIRE 16 -1 (-3250 3775)(-3250 3850);
WIRE 16 -1 (-2100 3775)(-2100 3850);
WIRE 16 -1 (-1375 3850)(-2100 3850);
FORCEPROP 2 LAST SIG_NAME PWRGD_P5V_AUX_R2
J 0
(-1975 3860);
DISPLAY 0.553191 (-1975 3860);
PAINT WHITE (-1975 3860);
FORCEPROP 2 LASTPROP $XRERR UNIQUE?
J 0
(-2215 3860);
DISPLAY 0.638298 (-2215 3860);
PAINT MONO (-2215 3860);
DISPLAY INVISIBLE (-2215 3860);
WIRE 16 -1 (-2100 4000)(-2100 3850);
WIRE 16 -1 (-925 3725)(-925 3850);
WIRE 16 -1 (-925 3850)(-625 3850);
WIRE 16 -1 (-1175 3850)(-925 3850);
FORCEPROP 2 LAST SIG_NAME PWRGD_P5V_AUX_R3
J 0
(-1050 3860);
DISPLAY 0.553191 (-1050 3860);
PAINT WHITE (-1050 3860);
WIRE 16 -1 (-3500 3525)(-4225 3525);
FORCEPROP 0 LAST SIG_NAME PWRGD_P5V_AUX
J 0
(-4135 3535);
DISPLAY 0.680851 (-4135 3535);
PAINT WHITE (-4135 3535);
WIRE 16 -1 (-4225 3800)(-4225 3525);
WIRE 16 -1 (-4225 3525)(-4300 3525);
WIRE 16 -1 (-7450 1425)(-6775 1425);
FORCEPROP 2 LAST SIG_NAME LED_HDD_ACTIVITY_B_PLD_N
J 0
(-7300 1435);
DISPLAY 0.446809 (-7300 1435);
PAINT WHITE (-7300 1435);
WIRE 16 -1 (-7450 1550)(-6775 1550);
FORCEPROP 2 LAST SIG_NAME FM_THERMAL_ALERT_R_N
J 0
(-7300 1560);
DISPLAY 0.446809 (-7300 1560);
PAINT WHITE (-7300 1560);
WIRE 16 -1 (-3425 1775)(-2675 1775);
FORCEPROP 2 LAST SIG_NAME JTAG_SCM_PLD_TDO
J 0
(-3425 1785);
DISPLAY 0.489362 (-3425 1785);
WIRE 16 -1 (-7475 4100)(-7475 4150);
WIRE 16 -1 (-6575 4150)(-7475 4150);
FORCEPROP 2 LAST SIG_NAME IRQ_HSC_FAULT
J 0
(-7210 4160);
DISPLAY 0.680851 (-7210 4160);
FORCEPROP 2 LASTPROP $XRERR UNIQUE?
J 0
(-7450 4160);
DISPLAY 0.638298 (-7450 4160);
PAINT MONO (-7450 4160);
DISPLAY INVISIBLE (-7450 4160);
WIRE 16 -1 (-7475 4400)(-7475 4150);
WIRE 16 -1 (-5325 4450)(-5550 4450);
WIRE 16 -1 (-5325 5075)(-5325 4450);
WIRE 16 -1 (-5250 4450)(-5325 4450);
WIRE 16 -1 (-5550 4250)(-5550 4450);
WIRE 16 -1 (-5550 4450)(-6325 4450);
FORCEPROP 2 LAST SIG_NAME IRQ_HSC_FAULT_BUF_N
J 0
(-6010 4485);
DISPLAY 0.680851 (-6010 4485);
WIRE 16 -1 (-6325 4525)(-6325 4450);
WIRE 16 -1 (-6325 4450)(-6325 4400);
WIRE 16 -1 (-6975 5075)(-5325 5075);
WIRE 16 -1 (-8850 3850)(-8625 3850);
WIRE 16 -1 (-7950 3850)(-8625 3850);
FORCEPROP 2 LAST SIG_NAME IRQ_HSC_FAULT_N
J 0
(-8485 3860);
DISPLAY 0.723404 (-8485 3860);
WIRE 16 -1 (-8625 3750)(-8625 3850);
WIRE 16 -1 (-7950 3850)(-7950 5075);
WIRE 16 -1 (-7725 3850)(-7950 3850);
WIRE 16 -1 (-7950 5075)(-7175 5075);
DOT 1 (-5325 4450);
DOT 1 (-5550 4450);
DOT 1 (-6325 4450);
DOT 1 (-7475 4150);
DOT 1 (-7950 3850);
DOT 1 (-8625 3850);
DOT 1 (-4225 3525);
DOT 1 (-3250 3850);
DOT 1 (-2100 3850);
DOT 1 (-925 3850);
DOT 1 (-3925 6050);
DOT 1 (-1725 2250);
DOT 1 (-2950 1525);
DOT 1 (-7825 875);
DOT 1 (-7150 775);
CIRCLE (-6700 500)(-6540 500);
PAINT YELLOW (-6700 500);
DOT 1 (-7850 1925);
FORCENOTE
CAD NOTE: IF DEPOP R530, PLEASE POP R556
(-6875 5800) 0;
DISPLAY LEFT (-6875 5800);
DISPLAY 1.021277 (-6875 5800);
FORCENOTE
CAD NOTE: IF DEPOP R1422, PLEASE POP R557
(-9200 5750) 0;
DISPLAY LEFT (-9200 5750);
DISPLAY 1.021277 (-9200 5750);
FORCENOTE
PIN3: PROGRAMMER TDO
(-1375 1750) 0;
DISPLAY LEFT (-1375 1750);
DISPLAY 1.021277 (-1375 1750);
FORCENOTE
PIN2: PROGRAMMER TDI
(-1375 1825) 0;
DISPLAY LEFT (-1375 1825);
DISPLAY 1.021277 (-1375 1825);
FORCENOTE
TBC
(-6750 475) 0;
DISPLAY LEFT (-6750 475);
DISPLAY 1.021277 (-6750 475);
FORCENOTE
PLACE THE 100PF CAPS FOR SI AND CLOSE TO MAIN PLD
(-8025 125) 0;
DISPLAY LEFT (-8025 125);
DISPLAY 1.021277 (-8025 125);
QUIT
